G04 ================== begin FILE IDENTIFICATION RECORD ==================*
G04 Layout Name:  14629-1a.brd*
G04 Film Name:    DRILL*
G04 File Format:  Gerber RS274X*
G04 File Origin:  Cadence Allegro 16.5-S037*
G04 Origin Date:  Tue Nov 25 11:50:41 2014*
G04 *
G04 Layer:  MANUFACTURING/NCLEGEND-1-4*
G04 Layer:  MANUFACTURING/DRILL SIZE*
G04 Layer:  DRAWING FORMAT/LAYER_PCB_STORY*
G04 Layer:  DRAWING FORMAT/LAYER_DRILL*
G04 Layer:  BOARD GEOMETRY/PANEL_OUTLINE*
G04 *
G04 Offset:    (0.00 0.00)*
G04 Mirror:    No*
G04 Mode:      Positive*
G04 Rotation:  0*
G04 FullContactRelief:  No*
G04 UndefLineWidth:     6.00*
G04 ================== end FILE IDENTIFICATION RECORD ====================*
%FSLAX35Y35*MOIN*%
%IR0*IPPOS*OFA0.00000B0.00000*MIA0B0*SFA1.00000B1.00000*%
%AMMACRO10*
1,1,.006,0.0,.043*
20,1,.006,0.0,.043,.043,-.043,0.0*
1,1,.006,.043,-.043*
20,1,.006,.043,-.043,-.043,-.043,0.0*
1,1,.006,-.043,-.043*
20,1,.006,-.043,-.043,0.0,.043,0.0*
1,1,.006,0.0,.043*
1,1,.006,-.00143,-.0215*
20,1,.006,-.00143,-.0215,0.0,-.01218,0.0*
1,1,.006,0.0,-.01218*
20,1,.006,0.0,-.01218,.00215,-.0043,0.0*
1,1,.006,.00215,-.0043*
20,1,.006,.00215,-.0043,.00502,.00287,0.0*
1,1,.006,.00502,.00287*
20,1,.006,.00502,.00287,.0086,.01075,0.0*
1,1,.006,.0086,.01075*
20,1,.006,.0086,.01075,.01433,.0215,0.0*
1,1,.006,.01433,.0215*
20,1,.006,.01433,.0215,-.01433,.0215,0.0*
1,1,.006,-.01433,.0215*
%
%ADD10MACRO10*%
%AMMACRO11*
1,1,.006,.028995,-.07*
20,1,.006,.028995,-.07,-.028995,-.07,0.0*
1,1,.006,-.028995,-.07*
20,1,.006,-.028995,-.07,-.07,-.028995,0.0*
1,1,.006,-.07,-.028995*
20,1,.006,-.07,-.028995,-.07,.028995,0.0*
1,1,.006,-.07,.028995*
20,1,.006,-.07,.028995,-.028995,.07,0.0*
1,1,.006,-.028995,.07*
20,1,.006,-.028995,.07,.028995,.07,0.0*
1,1,.006,.028995,.07*
20,1,.006,.028995,.07,.07,.028995,0.0*
1,1,.006,.07,.028995*
20,1,.006,.07,.028995,.07,-.028995,0.0*
1,1,.006,.07,-.028995*
20,1,.006,.07,-.028995,.028995,-.07,0.0*
1,1,.006,.028995,-.07*
1,1,.006,-.02567,-.0245*
20,1,.006,-.02567,-.0245,-.01867,-.03033,0.0*
1,1,.006,-.01867,-.03033*
20,1,.006,-.01867,-.03033,-.0105,-.03383,0.0*
1,1,.006,-.0105,-.03383*
20,1,.006,-.0105,-.03383,0.0,-.035,0.0*
1,1,.006,0.0,-.035*
20,1,.006,0.0,-.035,.0105,-.03267,0.0*
1,1,.006,.0105,-.03267*
20,1,.006,.0105,-.03267,.01867,-.028,0.0*
1,1,.006,.01867,-.028*
20,1,.006,.01867,-.028,.0245,-.01983,0.0*
1,1,.006,.0245,-.01983*
20,1,.006,.0245,-.01983,.02567,-.0105,0.0*
1,1,.006,.02567,-.0105*
20,1,.006,.02567,-.0105,.02333,-.00117,0.0*
1,1,.006,.02333,-.00117*
20,1,.006,.02333,-.00117,.0175,.00467,0.0*
1,1,.006,.0175,.00467*
20,1,.006,.0175,.00467,.00933,.00933,0.0*
1,1,.006,.00933,.00933*
20,1,.006,.00933,.00933,.00117,.0105,0.0*
1,1,.006,.00117,.0105*
20,1,.006,.00117,.0105,-.007,.00933,0.0*
1,1,.006,-.007,.00933*
20,1,.006,-.007,.00933,-.0175,.00467,0.0*
1,1,.006,-.0175,.00467*
20,1,.006,-.0175,.00467,-.014,.035,0.0*
1,1,.006,-.014,.035*
20,1,.006,-.014,.035,.0175,.035,0.0*
1,1,.006,.0175,.035*
%
%ADD11MACRO11*%
%AMMACRO12*
1,1,.006,.008,0.0*
20,1,.006,.008,0.0,-.008,0.0,0.0*
1,1,.006,-.008,0.0*
1,1,.006,0.0,.008*
20,1,.006,0.0,.008,0.0,-.008,0.0*
1,1,.006,0.0,-.008*
1,1,.006,.004,0.0*
20,1,.006,.004,0.0,.004,.008,0.0*
1,1,.006,.004,.008*
20,1,.006,.004,.008,.0024,.0064,0.0*
1,1,.006,.0024,.0064*
1,1,.006,.0024,0.0*
20,1,.006,.0024,0.0,.0056,0.0,0.0*
1,1,.006,.0056,0.0*
%
%ADD12MACRO12*%
%AMMACRO16*
1,1,.006,.018,.018*
20,1,.006,.018,.018,.018,-.018,0.0*
1,1,.006,.018,-.018*
20,1,.006,.018,-.018,-.018,-.018,0.0*
1,1,.006,-.018,-.018*
20,1,.006,-.018,-.018,-.018,.018,0.0*
1,1,.006,-.018,.018*
20,1,.006,-.018,.018,.018,.018,0.0*
1,1,.006,.018,.018*
1,1,.006,-.0057,.006*
20,1,.006,-.0057,.006,-.0039,.0078,0.0*
1,1,.006,-.0039,.0078*
20,1,.006,-.0039,.0078,-.0018,.0087,0.0*
1,1,.006,-.0018,.0087*
20,1,.006,-.0018,.0087,.0006,.009,0.0*
1,1,.006,.0006,.009*
20,1,.006,.0006,.009,.0036,.0084,0.0*
1,1,.006,.0036,.0084*
20,1,.006,.0036,.0084,.0057,.0069,0.0*
1,1,.006,.0057,.0069*
20,1,.006,.0057,.0069,.0063,.0051,0.0*
1,1,.006,.0063,.0051*
20,1,.006,.0063,.0051,.006,.0033,0.0*
1,1,.006,.006,.0033*
20,1,.006,.006,.0033,.0048,.0018,0.0*
1,1,.006,.0048,.0018*
20,1,.006,.0048,.0018,-.0012,-.0012,0.0*
1,1,.006,-.0012,-.0012*
20,1,.006,-.0012,-.0012,-.0039,-.0033,0.0*
1,1,.006,-.0039,-.0033*
20,1,.006,-.0039,-.0033,-.0057,-.0063,0.0*
1,1,.006,-.0057,-.0063*
20,1,.006,-.0057,-.0063,-.0063,-.009,0.0*
1,1,.006,-.0063,-.009*
20,1,.006,-.0063,-.009,.0063,-.009,0.0*
1,1,.006,.0063,-.009*
%
%ADD16MACRO16*%
%AMMACRO13*
1,1,.006,.079,0.0*
20,1,.006,.079,0.0,0.0,-.079,0.0*
1,1,.006,0.0,-.079*
20,1,.006,0.0,-.079,-.079,0.0,0.0*
1,1,.006,-.079,0.0*
20,1,.006,-.079,0.0,0.0,.079,0.0*
1,1,.006,0.0,.079*
20,1,.006,0.0,.079,.079,0.0,0.0*
1,1,.006,.079,0.0*
1,1,.006,-.02502,-.00659*
20,1,.006,-.02502,-.00659,-.0158,.00263,0.0*
1,1,.006,-.0158,.00263*
20,1,.006,-.0158,.00263,-.0079,.0079,0.0*
1,1,.006,-.0079,.0079*
20,1,.006,-.0079,.0079,.00263,.01053,0.0*
1,1,.006,.00263,.01053*
20,1,.006,.00263,.01053,.01185,.0079,0.0*
1,1,.006,.01185,.0079*
20,1,.006,.01185,.0079,.01843,.00263,0.0*
1,1,.006,.01843,.00263*
20,1,.006,.01843,.00263,.0237,-.00527,0.0*
1,1,.006,.0237,-.00527*
20,1,.006,.0237,-.00527,.02502,-.01448,0.0*
1,1,.006,.02502,-.01448*
20,1,.006,.02502,-.01448,.0237,-.02238,0.0*
1,1,.006,.0237,-.02238*
20,1,.006,.0237,-.02238,.01843,-.03029,0.0*
1,1,.006,.01843,-.03029*
20,1,.006,.01843,-.03029,.01053,-.03687,0.0*
1,1,.006,.01053,-.03687*
20,1,.006,.01053,-.03687,.00132,-.0395,0.0*
1,1,.006,.00132,-.0395*
20,1,.006,.00132,-.0395,-.00922,-.03687,0.0*
1,1,.006,-.00922,-.03687*
20,1,.006,-.00922,-.03687,-.01843,-.02897,0.0*
1,1,.006,-.01843,-.02897*
20,1,.006,-.01843,-.02897,-.0237,-.01712,0.0*
1,1,.006,-.0237,-.01712*
20,1,.006,-.0237,-.01712,-.02502,-.00395,0.0*
1,1,.006,-.02502,-.00395*
20,1,.006,-.02502,-.00395,-.02238,.01317,0.0*
1,1,.006,-.02238,.01317*
20,1,.006,-.02238,.01317,-.01843,.02238,0.0*
1,1,.006,-.01843,.02238*
20,1,.006,-.01843,.02238,-.01185,.0316,0.0*
1,1,.006,-.01185,.0316*
20,1,.006,-.01185,.0316,-.00263,.03818,0.0*
1,1,.006,-.00263,.03818*
20,1,.006,-.00263,.03818,.00658,.0395,0.0*
1,1,.006,.00658,.0395*
20,1,.006,.00658,.0395,.0158,.03687,0.0*
1,1,.006,.0158,.03687*
20,1,.006,.0158,.03687,.02238,.03028,0.0*
1,1,.006,.02238,.03028*
%
%ADD13MACRO13*%
%AMMACRO14*
1,1,.006,.0205,0.0*
20,1,.006,.0205,0.0,.01025,.017754,0.0*
1,1,.006,.01025,.017754*
20,1,.006,.01025,.017754,-.01025,.017754,0.0*
1,1,.006,-.01025,.017754*
20,1,.006,-.01025,.017754,-.0205,0.0,0.0*
1,1,.006,-.0205,0.0*
20,1,.006,-.0205,0.0,-.01025,-.017754,0.0*
1,1,.006,-.01025,-.017754*
20,1,.006,-.01025,-.017754,.01025,-.017754,0.0*
1,1,.006,.01025,-.017754*
20,1,.006,.01025,-.017754,.0205,0.0,0.0*
1,1,.006,.0205,0.0*
1,1,.006,-.00752,-.00615*
20,1,.006,-.00752,-.00615,-.00547,-.00854,0.0*
1,1,.006,-.00547,-.00854*
20,1,.006,-.00547,-.00854,-.00273,-.00991,0.0*
1,1,.006,-.00273,-.00991*
20,1,.006,-.00273,-.00991,.00034,-.01025,0.0*
1,1,.006,.00034,-.01025*
20,1,.006,.00034,-.01025,.00308,-.00991,0.0*
1,1,.006,.00308,-.00991*
20,1,.006,.00308,-.00991,.00581,-.0082,0.0*
1,1,.006,.00581,-.0082*
20,1,.006,.00581,-.0082,.00752,-.00615,0.0*
1,1,.006,.00752,-.00615*
20,1,.006,.00752,-.00615,.00786,-.0041,0.0*
1,1,.006,.00786,-.0041*
20,1,.006,.00786,-.0041,.00718,-.00171,0.0*
1,1,.006,.00718,-.00171*
20,1,.006,.00718,-.00171,.00478,0.0,0.0*
1,1,.006,.00478,0.0*
20,1,.006,.00478,0.0,.00239,.00068,0.0*
1,1,.006,.00239,.00068*
20,1,.006,.00239,.00068,-.00068,.00068,0.0*
1,1,.006,-.00068,.00068*
1,1,.006,.00239,.00068*
20,1,.006,.00239,.00068,.00444,.00171,0.0*
1,1,.006,.00444,.00171*
20,1,.006,.00444,.00171,.00615,.00342,0.0*
1,1,.006,.00615,.00342*
20,1,.006,.00615,.00342,.00683,.00547,0.0*
1,1,.006,.00683,.00547*
20,1,.006,.00683,.00547,.00615,.00752,0.0*
1,1,.006,.00615,.00752*
20,1,.006,.00615,.00752,.00444,.00922,0.0*
1,1,.006,.00444,.00922*
20,1,.006,.00444,.00922,.00137,.01025,0.0*
1,1,.006,.00137,.01025*
20,1,.006,.00137,.01025,-.00171,.00991,0.0*
1,1,.006,-.00171,.00991*
20,1,.006,-.00171,.00991,-.00478,.00854,0.0*
1,1,.006,-.00478,.00854*
%
%ADD14MACRO14*%
%AMMACRO17*
1,1,.006,-.01975,.05925*
20,1,.006,-.01975,.05925,.01975,.05925,0.0*
1,1,.006,.01975,.05925*
20,1,.006,.01975,.05925,.030039,.05835,0.0*
1,1,.006,.030039,.05835*
20,1,.006,.030039,.05835,.040015,.055677,0.0*
1,1,.006,.040015,.055677*
20,1,.006,.040015,.055677,.049375,.051312,0.0*
1,1,.006,.049375,.051312*
20,1,.006,.049375,.051312,.057835,.045388,0.0*
1,1,.006,.057835,.045388*
20,1,.006,.057835,.045388,.065138,.038085,0.0*
1,1,.006,.065138,.038085*
20,1,.006,.065138,.038085,.071062,.029625,0.0*
1,1,.006,.071062,.029625*
20,1,.006,.071062,.029625,.075427,.020265,0.0*
1,1,.006,.075427,.020265*
20,1,.006,.075427,.020265,.0781,.010289,0.0*
1,1,.006,.0781,.010289*
20,1,.006,.0781,.010289,.079,0.0,0.0*
1,1,.006,.079,0.0*
20,1,.006,.079,0.0,.0781,-.010289,0.0*
1,1,.006,.0781,-.010289*
20,1,.006,.0781,-.010289,.075427,-.020265,0.0*
1,1,.006,.075427,-.020265*
20,1,.006,.075427,-.020265,.071062,-.029625,0.0*
1,1,.006,.071062,-.029625*
20,1,.006,.071062,-.029625,.065138,-.038085,0.0*
1,1,.006,.065138,-.038085*
20,1,.006,.065138,-.038085,.057835,-.045388,0.0*
1,1,.006,.057835,-.045388*
20,1,.006,.057835,-.045388,.049375,-.051312,0.0*
1,1,.006,.049375,-.051312*
20,1,.006,.049375,-.051312,.040015,-.055677,0.0*
1,1,.006,.040015,-.055677*
20,1,.006,.040015,-.055677,.030039,-.05835,0.0*
1,1,.006,.030039,-.05835*
20,1,.006,.030039,-.05835,.01975,-.05925,0.0*
1,1,.006,.01975,-.05925*
20,1,.006,.01975,-.05925,-.01975,-.05925,0.0*
1,1,.006,-.01975,-.05925*
20,1,.006,-.01975,-.05925,-.030039,-.05835,0.0*
1,1,.006,-.030039,-.05835*
20,1,.006,-.030039,-.05835,-.040015,-.055677,0.0*
1,1,.006,-.040015,-.055677*
20,1,.006,-.040015,-.055677,-.049375,-.051312,0.0*
1,1,.006,-.049375,-.051312*
20,1,.006,-.049375,-.051312,-.057835,-.045388,0.0*
1,1,.006,-.057835,-.045388*
20,1,.006,-.057835,-.045388,-.065138,-.038085,0.0*
1,1,.006,-.065138,-.038085*
20,1,.006,-.065138,-.038085,-.071062,-.029625,0.0*
1,1,.006,-.071062,-.029625*
20,1,.006,-.071062,-.029625,-.075427,-.020265,0.0*
1,1,.006,-.075427,-.020265*
20,1,.006,-.075427,-.020265,-.0781,-.010289,0.0*
1,1,.006,-.0781,-.010289*
20,1,.006,-.0781,-.010289,-.079,0.0,0.0*
1,1,.006,-.079,0.0*
20,1,.006,-.079,0.0,-.0781,.010289,0.0*
1,1,.006,-.0781,.010289*
20,1,.006,-.0781,.010289,-.075427,.020265,0.0*
1,1,.006,-.075427,.020265*
20,1,.006,-.075427,.020265,-.071062,.029625,0.0*
1,1,.006,-.071062,.029625*
20,1,.006,-.071062,.029625,-.065138,.038085,0.0*
1,1,.006,-.065138,.038085*
20,1,.006,-.065138,.038085,-.057835,.045388,0.0*
1,1,.006,-.057835,.045388*
20,1,.006,-.057835,.045388,-.049375,.051312,0.0*
1,1,.006,-.049375,.051312*
20,1,.006,-.049375,.051312,-.040015,.055677,0.0*
1,1,.006,-.040015,.055677*
20,1,.006,-.040015,.055677,-.030039,.05835,0.0*
1,1,.006,-.030039,.05835*
20,1,.006,-.030039,.05835,-.01975,.05925,0.0*
1,1,.006,-.01975,.05925*
1,1,.006,0.0,-.02962*
20,1,.006,0.0,-.02962,.00692,-.02863,0.0*
1,1,.006,.00692,-.02863*
20,1,.006,.00692,-.02863,.01482,-.02567,0.0*
1,1,.006,.01482,-.02567*
20,1,.006,.01482,-.02567,.01976,-.02073,0.0*
1,1,.006,.01976,-.02073*
20,1,.006,.01976,-.02073,.02173,-.01382,0.0*
1,1,.006,.02173,-.01382*
20,1,.006,.02173,-.01382,.01976,-.00691,0.0*
1,1,.006,.01976,-.00691*
20,1,.006,.01976,-.00691,.01383,-.00098,0.0*
1,1,.006,.01383,-.00098*
20,1,.006,.01383,-.00098,.00494,.00198,0.0*
1,1,.006,.00494,.00198*
20,1,.006,.00494,.00198,-.00493,.00198,0.0*
1,1,.006,-.00493,.00198*
20,1,.006,-.00493,.00198,-.01086,.00396,0.0*
1,1,.006,-.01086,.00396*
20,1,.006,-.01086,.00396,-.0158,.00889,0.0*
1,1,.006,-.0158,.00889*
20,1,.006,-.0158,.00889,-.01777,.0158,0.0*
1,1,.006,-.01777,.0158*
20,1,.006,-.01777,.0158,-.01481,.02272,0.0*
1,1,.006,-.01481,.02272*
20,1,.006,-.01481,.02272,-.0079,.02766,0.0*
1,1,.006,-.0079,.02766*
20,1,.006,-.0079,.02766,0.0,.02963,0.0*
1,1,.006,0.0,.02963*
20,1,.006,0.0,.02963,.0079,.02766,0.0*
1,1,.006,.0079,.02766*
20,1,.006,.0079,.02766,.01482,.02272,0.0*
1,1,.006,.01482,.02272*
20,1,.006,.01482,.02272,.01778,.0158,0.0*
1,1,.006,.01778,.0158*
20,1,.006,.01778,.0158,.0158,.00889,0.0*
1,1,.006,.0158,.00889*
20,1,.006,.0158,.00889,.01087,.00396,0.0*
1,1,.006,.01087,.00396*
20,1,.006,.01087,.00396,.00494,.00198,0.0*
1,1,.006,.00494,.00198*
20,1,.006,.00494,.00198,-.00493,.00198,0.0*
1,1,.006,-.00493,.00198*
20,1,.006,-.00493,.00198,-.01382,-.00098,0.0*
1,1,.006,-.01382,-.00098*
20,1,.006,-.01382,-.00098,-.01975,-.00691,0.0*
1,1,.006,-.01975,-.00691*
20,1,.006,-.01975,-.00691,-.02172,-.01382,0.0*
1,1,.006,-.02172,-.01382*
20,1,.006,-.02172,-.01382,-.01975,-.02073,0.0*
1,1,.006,-.01975,-.02073*
20,1,.006,-.01975,-.02073,-.01481,-.02567,0.0*
1,1,.006,-.01481,-.02567*
20,1,.006,-.01481,-.02567,-.00691,-.02863,0.0*
1,1,.006,-.00691,-.02863*
20,1,.006,-.00691,-.02863,0.0,-.02962,0.0*
1,1,.006,0.0,-.02962*
%
%ADD17MACRO17*%
%AMMACRO15*
1,1,.006,0.0,.024*
20,1,.006,0.0,.024,-.020785,.012,0.0*
1,1,.006,-.020785,.012*
20,1,.006,-.020785,.012,-.020785,-.012,0.0*
1,1,.006,-.020785,-.012*
20,1,.006,-.020785,-.012,0.0,-.024,0.0*
1,1,.006,0.0,-.024*
20,1,.006,0.0,-.024,.020785,-.012,0.0*
1,1,.006,.020785,-.012*
20,1,.006,.020785,-.012,.020785,.012,0.0*
1,1,.006,.020785,.012*
20,1,.006,.020785,.012,0.0,.024,0.0*
1,1,.006,0.0,.024*
1,1,.006,.0048,-.012*
20,1,.006,.0048,-.012,.0048,.012,0.0*
1,1,.006,.0048,.012*
20,1,.006,.0048,.012,-.01,-.0052,0.0*
1,1,.006,-.01,-.0052*
20,1,.006,-.01,-.0052,.01,-.0052,0.0*
1,1,.006,.01,-.0052*
%
%ADD15MACRO15*%
%ADD18C,.02*%
%ADD19C,.006*%
G75*
%LPD*%
G75*
G54D10*
X-23621Y15748D03*
Y937008D03*
X1312285Y15747D03*
X1312281Y889328D03*
X1453450Y113650D03*
G54D11*
X30157Y61023D03*
Y415354D03*
X1453450Y169850D03*
G54D12*
X6419Y116482D03*
X-3350Y117504D03*
X6419Y126482D03*
X-3581D03*
X6419Y136482D03*
X-3581D03*
X6419Y146482D03*
X-3581D03*
X6419Y156482D03*
X-3581D03*
X-2602Y206936D03*
X7398D03*
X-2602Y216936D03*
X7398D03*
X6419Y166482D03*
X-3581D03*
Y176482D03*
X6419D03*
X-2602Y226936D03*
X7398D03*
X-2602Y246936D03*
X7398D03*
X-2602Y236936D03*
X7398D03*
Y256936D03*
X-2602D03*
Y266936D03*
X7398D03*
Y276936D03*
X-2602D03*
X7398Y286936D03*
X3398Y326936D03*
X-2948Y302202D03*
X-2602Y316436D03*
X-7102Y327202D03*
X-6940Y316247D03*
X2334Y318654D03*
X1494Y343705D03*
X5694D03*
X-6602Y347202D03*
X-7102Y337202D03*
X-6602Y357202D03*
X6898Y387436D03*
X6398Y369936D03*
X6898Y445436D03*
Y465436D03*
X16419Y6482D03*
Y26482D03*
X36419Y6482D03*
Y26482D03*
X56419Y46482D03*
X16419Y86482D03*
X36419D03*
X56419Y66482D03*
Y86482D03*
X26419Y116482D03*
X16419D03*
X26419Y126482D03*
X16419D03*
X26419Y136482D03*
X16419D03*
X26419Y146482D03*
X16419D03*
X26419Y156482D03*
X16419D03*
X36419Y126482D03*
X16419Y106482D03*
X36419D03*
Y146482D03*
X56419Y126482D03*
Y106482D03*
Y146482D03*
X27398Y206936D03*
X17398D03*
X27398Y216936D03*
X17398D03*
X26419Y186482D03*
X16419D03*
X26419Y166482D03*
X16419D03*
Y176482D03*
X26419D03*
X36419Y186482D03*
Y166482D03*
X56419Y186482D03*
Y166482D03*
X57398Y206936D03*
X37398D03*
X17398Y256936D03*
X27398D03*
Y266936D03*
X17398D03*
X57398Y226936D03*
X36769D03*
X57398Y246936D03*
Y266936D03*
X36769Y246936D03*
X37398Y266936D03*
X17398Y276936D03*
X27398Y286936D03*
X17398D03*
X27398Y276936D03*
X10000Y332000D03*
X57398Y286936D03*
X37398D03*
X64398Y304436D03*
X30923Y335665D03*
X25500Y353000D03*
X25000Y343000D03*
X33986Y362933D03*
X26723Y335665D03*
X22000Y374500D03*
X34898Y344936D03*
X57398Y348682D03*
X52705Y348626D03*
X48325Y348514D03*
X62398Y338436D03*
X37500Y386500D03*
X22000Y387500D03*
X61898Y358936D03*
X62000Y442500D03*
X60052Y394674D03*
X35830Y442464D03*
X55352Y394674D03*
X51094Y394478D03*
X55500Y417000D03*
X19898Y465436D03*
X39898D03*
X76419Y46482D03*
X116419D03*
X96419D03*
X76419Y66482D03*
Y86482D03*
X116419Y66482D03*
X96419D03*
X116419Y86482D03*
X96419D03*
X76419Y126482D03*
Y106482D03*
Y146482D03*
X116419Y126482D03*
Y106482D03*
X96419Y126482D03*
Y106482D03*
X116419Y146482D03*
X96419D03*
X76419Y186482D03*
Y166482D03*
X77398Y206936D03*
X116419Y186482D03*
Y166482D03*
X96419Y186482D03*
Y166482D03*
X117398Y206936D03*
X97398D03*
X77398Y226936D03*
Y246936D03*
Y266936D03*
X117398Y226936D03*
X97398D03*
X117398Y246936D03*
X97398D03*
Y266936D03*
X116398D03*
X77398Y286936D03*
X86398Y303936D03*
X97398Y286936D03*
X116398D03*
X77898Y338436D03*
X78398Y358436D03*
X115330Y337964D03*
X96398Y337936D03*
X115330Y377964D03*
Y357964D03*
X95330Y377964D03*
Y357964D03*
X105330Y442964D03*
X85330D03*
X75500Y417500D03*
X115330Y417964D03*
X95330D03*
X91500Y465500D03*
X117500D03*
X67830Y465464D03*
X136419Y6482D03*
Y46482D03*
X176419Y6482D03*
Y26482D03*
X156419Y6482D03*
Y26482D03*
X176419Y46482D03*
X156419D03*
X136419Y66482D03*
Y86482D03*
X176419Y66482D03*
X156419D03*
X176419Y86482D03*
X156419D03*
X136419Y126482D03*
Y106482D03*
Y146482D03*
X176419Y126482D03*
Y106482D03*
X156419Y126482D03*
Y106482D03*
X176419Y146482D03*
X156419D03*
X136419Y186482D03*
Y166482D03*
X137398Y206936D03*
X176419Y186482D03*
Y166482D03*
X156419Y186482D03*
Y166482D03*
X177398Y206436D03*
X157398Y206936D03*
X137398Y226936D03*
Y246936D03*
Y266936D03*
X177398Y226936D03*
X157398D03*
X177398Y246936D03*
Y266936D03*
X157398Y246936D03*
Y266936D03*
X137398Y286936D03*
X177398D03*
X157398D03*
X135330Y337964D03*
Y377964D03*
Y357964D03*
X175330Y337964D03*
X155330D03*
X175330Y377964D03*
Y357964D03*
X155330Y377964D03*
Y357964D03*
X132000Y442500D03*
X135330Y417964D03*
X175500Y442000D03*
X175330Y417964D03*
X155000Y442000D03*
X155330Y417964D03*
X139898Y465436D03*
X159898D03*
X196419Y6482D03*
Y26482D03*
Y46482D03*
X236419Y6482D03*
Y26482D03*
X216419Y6482D03*
Y26482D03*
X236419Y46482D03*
X216419D03*
X196419Y66482D03*
Y86482D03*
X236419Y66482D03*
X216419D03*
X236419Y86482D03*
X216419D03*
X196419Y126482D03*
Y106482D03*
Y146482D03*
X236419Y126482D03*
Y106482D03*
X216419Y126482D03*
Y106482D03*
X236419Y146482D03*
X216419D03*
X196419Y186482D03*
Y166482D03*
X197398Y206436D03*
X236419Y186482D03*
Y166482D03*
X216419Y186482D03*
Y166482D03*
X217398Y206436D03*
X197398Y226936D03*
Y246936D03*
Y266936D03*
X217398Y226936D03*
Y246936D03*
Y266936D03*
X197398Y286936D03*
X217398D03*
X195330Y337964D03*
Y377964D03*
Y357964D03*
X235330Y337964D03*
X215330D03*
X235330Y377964D03*
Y357964D03*
X215330Y377964D03*
Y357964D03*
X196000Y442500D03*
X195330Y417964D03*
X235830Y442464D03*
X235330Y417964D03*
X215830Y442464D03*
X215330Y417964D03*
X179898Y465436D03*
X219898D03*
X199898D03*
X256419Y6482D03*
Y26482D03*
X276419Y6482D03*
Y26482D03*
X256419Y46482D03*
X276419D03*
X256419Y66482D03*
X273500Y66500D03*
X256419Y86482D03*
X274500Y86500D03*
X256419Y126482D03*
X276419D03*
X256419Y106482D03*
X274500Y106500D03*
X256419Y146482D03*
X276419D03*
X237398Y206436D03*
X256419Y186482D03*
X275500Y186500D03*
X251500Y166500D03*
X276419Y166482D03*
X257398Y206436D03*
X277398D03*
X237398Y226936D03*
Y246936D03*
Y266936D03*
X257398Y226936D03*
X277398D03*
X257398Y246936D03*
X277398D03*
X257398Y266936D03*
X277398D03*
X237398Y286936D03*
X257398D03*
X279398D03*
X255330Y337964D03*
X275330D03*
X255330Y377964D03*
X275330D03*
X255330Y357964D03*
X275330D03*
X255830Y442464D03*
X275830D03*
X255330Y417964D03*
X275330D03*
X239898Y465436D03*
X279898D03*
X259898D03*
X296419Y6482D03*
Y26482D03*
Y46482D03*
X316419Y6482D03*
Y26482D03*
X336419Y6482D03*
Y26482D03*
X316419Y46482D03*
X336419D03*
X302000Y67000D03*
X301000Y86500D03*
X316419Y66482D03*
X336419D03*
X316419Y86482D03*
X336419D03*
X296419Y126482D03*
X300000Y106500D03*
X296419Y146482D03*
X316419Y126482D03*
X336419D03*
X316419Y106482D03*
X336419D03*
X316419Y146482D03*
X336419D03*
X296419Y186482D03*
X295500Y169000D03*
X297398Y206436D03*
X317500Y186500D03*
X336419Y186482D03*
X317000Y166500D03*
X338500Y166000D03*
X317398Y206436D03*
X337398D03*
X297398Y226936D03*
Y246936D03*
Y266936D03*
X317398Y226936D03*
X337398D03*
X317398Y246936D03*
X337398D03*
X317398Y266936D03*
X337398D03*
X300398Y286936D03*
X317398D03*
X337398D03*
X295330Y337964D03*
Y377964D03*
Y357964D03*
X315330Y337964D03*
X335330D03*
X315330Y377964D03*
X335330D03*
X315330Y357964D03*
X335330D03*
X295830Y442464D03*
X295330Y417964D03*
X315830Y442464D03*
X335830D03*
X315330Y417964D03*
X335330D03*
X299898Y465436D03*
X339898D03*
X319898D03*
X356419Y6482D03*
Y26482D03*
Y46482D03*
X376419Y6482D03*
Y26482D03*
X396419Y6482D03*
Y26482D03*
X376419Y46482D03*
X396419D03*
X356419Y66482D03*
Y86482D03*
X376419Y66482D03*
X396419D03*
X376419Y86482D03*
X396419D03*
X356419Y126482D03*
Y106482D03*
Y146482D03*
X376419Y126482D03*
X396419D03*
X376419Y106482D03*
X396419D03*
X376419Y146482D03*
X396419D03*
X357500Y186500D03*
X354500Y166500D03*
X357398Y206436D03*
X376419Y186482D03*
X396419D03*
X380000Y166500D03*
X396419Y166482D03*
X377398Y206436D03*
X397398D03*
X357398Y226936D03*
Y246936D03*
Y266936D03*
X377398Y226936D03*
X397398D03*
X377398Y246936D03*
X397398D03*
X377398Y266936D03*
X397398D03*
X357398Y286936D03*
X377398D03*
X397398D03*
X355330Y337964D03*
Y377964D03*
Y357964D03*
X375330Y337964D03*
X395330D03*
X375330Y377964D03*
X395330D03*
X375330Y357964D03*
X395330D03*
X355830Y442464D03*
X355330Y417964D03*
X375830Y442464D03*
X395830D03*
X375330Y417964D03*
X395330D03*
X399898Y465436D03*
X379898D03*
X359898D03*
X416419Y6482D03*
Y26482D03*
X436419Y6482D03*
X416419Y46482D03*
X436419D03*
X456419D03*
X416419Y66482D03*
X436419D03*
X456419D03*
X416419Y86482D03*
X436419D03*
X456419D03*
X416419Y126482D03*
X436419D03*
X456419D03*
X416419Y106482D03*
X436419D03*
X456419D03*
X416419Y146482D03*
X436419D03*
X456419D03*
X416500Y166000D03*
X417519Y174482D03*
Y170282D03*
X425919D03*
X421719D03*
Y174482D03*
X431100Y174500D03*
Y170300D03*
X439500D03*
Y174500D03*
X435300Y170300D03*
Y174500D03*
X444100D03*
Y170300D03*
X452500D03*
Y174500D03*
X448300Y170300D03*
Y174500D03*
X457100Y175000D03*
Y170800D03*
X461300D03*
Y175000D03*
X418300Y197500D03*
Y201700D03*
X422500D03*
X426700D03*
X422500Y197500D03*
X426700D03*
X431300D03*
Y201700D03*
X435500D03*
X439700D03*
X435500Y197500D03*
X439700D03*
X444800D03*
Y201700D03*
X449000D03*
X453200D03*
X449000Y197500D03*
X453200D03*
X457800D03*
Y201700D03*
X462000D03*
Y197500D03*
X425919Y174482D03*
X436500Y166000D03*
X456500Y166500D03*
X417398Y206436D03*
X437398D03*
X457398D03*
X417398Y226936D03*
X437398D03*
X457398D03*
X417398Y246936D03*
X437398D03*
X457398D03*
X437398Y266936D03*
X457398D03*
X418398D03*
X437398Y286936D03*
X457398D03*
X418398D03*
X415330Y337964D03*
X435398Y338436D03*
X455398D03*
X415330Y377964D03*
Y357964D03*
X435398Y358436D03*
Y378436D03*
X455398Y358436D03*
Y378436D03*
X435830Y442464D03*
X435330Y417964D03*
X455330D03*
X415830Y442464D03*
X415330Y417964D03*
X454500Y465500D03*
X439898Y465436D03*
X419898D03*
X516419Y6482D03*
X476419Y46482D03*
X496419D03*
X516419D03*
Y66482D03*
X476419D03*
X496419D03*
X516419Y86482D03*
X496419D03*
X476419D03*
Y126482D03*
X516419D03*
X496419D03*
X516419Y106482D03*
X496419D03*
X476419D03*
X485443Y160670D03*
X481243D03*
X493843D03*
X489643D03*
X476419Y146482D03*
X516419D03*
X496419D03*
X519221Y160912D03*
X510821D03*
X506621D03*
X515021D03*
X465500Y170800D03*
Y175000D03*
X466200Y201700D03*
Y197500D03*
X485443Y164870D03*
X481243D03*
X493843D03*
X489643D03*
X477284Y174586D03*
X473084D03*
Y170386D03*
X477284D03*
X498395Y174685D03*
Y170485D03*
X492911Y206602D03*
X488711D03*
X492911Y210802D03*
X488711D03*
X484511D03*
Y206602D03*
X480311Y210802D03*
Y206602D03*
X498052Y200389D03*
Y196189D03*
X477087Y201172D03*
X472887D03*
X477087Y196972D03*
X472887D03*
X519221Y165112D03*
X510821D03*
X506621D03*
X515021D03*
X502595Y174685D03*
Y170485D03*
X506135Y210557D03*
X510335D03*
X514535D03*
X518735D03*
X506135Y206357D03*
X510335D03*
X514535D03*
X518735D03*
X502252Y200389D03*
Y196189D03*
X497398Y226936D03*
X477398D03*
X520898Y228436D03*
X497398Y246936D03*
X477398D03*
Y266936D03*
X512500Y323000D03*
X492000Y321000D03*
X506500Y305500D03*
X520500Y331000D03*
X520381Y300757D03*
X489500Y375500D03*
X485500D03*
X495398Y338436D03*
X475398D03*
X495398Y358436D03*
Y378436D03*
X475398Y358436D03*
Y378436D03*
X477000Y418000D03*
X499000Y418500D03*
X466500Y428000D03*
X533619Y6482D03*
Y26482D03*
Y46482D03*
X550819Y6482D03*
Y26482D03*
Y46482D03*
X568019Y6482D03*
Y26482D03*
Y46482D03*
X573623Y66967D03*
X536419Y66482D03*
X556419D03*
X536419Y86482D03*
X556419D03*
X576419Y106482D03*
Y126482D03*
X536419D03*
X556419D03*
X536419Y106482D03*
X556419D03*
X544476Y161322D03*
X531876D03*
X536076D03*
X540276D03*
X536419Y146482D03*
X556419D03*
X544477Y210389D03*
X544476Y165522D03*
X536076D03*
X531876D03*
X540276D03*
X552924Y175124D03*
X548724D03*
Y170924D03*
X552924D03*
X527711Y175174D03*
X523511D03*
Y170974D03*
X527711D03*
X531877Y210389D03*
X536077D03*
X540277D03*
X531877Y206189D03*
X536077D03*
X540277D03*
X544477D03*
X527761Y200632D03*
X523561D03*
X527761Y196432D03*
X523561D03*
X553171Y200877D03*
X548971D03*
X553171Y196677D03*
X548971D03*
X546600Y257971D03*
X540898Y228436D03*
X561500Y232000D03*
X557000Y231500D03*
X560500Y268000D03*
X549500Y305500D03*
X543900Y314000D03*
X559996Y282972D03*
X561500Y298000D03*
X534000Y282000D03*
X537136Y326402D03*
X525161Y311000D03*
X577500Y305000D03*
X548000Y442500D03*
X553000Y425000D03*
X568500Y464841D03*
X538000D03*
X634119Y26482D03*
X585219Y46482D03*
Y26482D03*
Y6482D03*
X602419Y26482D03*
Y6482D03*
X619619D03*
Y26482D03*
Y46482D03*
X634119D03*
Y6482D03*
X602419Y46482D03*
X628500Y104000D03*
X626500Y78500D03*
X611253Y65701D03*
X584543Y86671D03*
X611398Y86936D03*
X633753Y65701D03*
X633898Y86936D03*
X634000Y123500D03*
X607000D03*
X616000Y138000D03*
Y115500D03*
X594500Y117000D03*
X616000Y173500D03*
X615500Y199000D03*
X615898Y244436D03*
Y224436D03*
X615398Y266436D03*
X587500Y318500D03*
X600000Y298500D03*
X616498Y316236D03*
X615398Y284436D03*
X633398Y325436D03*
X630000Y345500D03*
X600000Y337500D03*
Y342000D03*
X595500D03*
Y337500D03*
X630000Y387500D03*
X612798Y413000D03*
X610898Y425436D03*
Y445436D03*
X617798Y413000D03*
X632898Y404936D03*
Y444936D03*
Y424936D03*
X592000Y464841D03*
X610898Y465436D03*
X632898Y464936D03*
X1453450Y282250D03*
G54D13*
X498661Y23622D03*
X518346Y448818D03*
X1453450Y141750D03*
G54D14*
X570709Y161889D03*
X580709D03*
X570709Y214409D03*
X580709D03*
X570709Y204409D03*
X580709D03*
X570709Y191889D03*
X580709D03*
X570709Y181889D03*
X580709D03*
X570709Y171889D03*
X580709D03*
X570709Y244409D03*
X580709D03*
X570709Y276929D03*
X580709D03*
X570709Y266929D03*
X580709D03*
X570709Y256929D03*
X580709D03*
X570709Y234409D03*
X580709D03*
X570709Y224409D03*
X580709D03*
X570709Y286929D03*
X580709D03*
X590709Y161889D03*
X600709D03*
X590709Y214409D03*
X600709D03*
X590709Y204409D03*
X600709D03*
X590709Y191889D03*
X600709D03*
X590709Y181889D03*
X600709D03*
X590709Y171889D03*
X600709D03*
X590709Y244409D03*
X600709D03*
X590709Y276929D03*
X600709D03*
X590709Y266929D03*
X600709D03*
X590709Y256929D03*
X600709D03*
X590709Y234409D03*
X600709D03*
X590709Y224409D03*
X600709D03*
X590709Y286929D03*
X600709D03*
X1453450Y226050D03*
G54D15*
X559489Y427559D03*
X603780Y442126D03*
X1453450Y197950D03*
G54D16*
X571496Y433071D03*
X581339D03*
X591182D03*
X1453450Y254150D03*
G54D17*
X600709Y136909D03*
Y311909D03*
X1453450Y85550D03*
G54D18*
G01X-4246Y-109426D02*
Y-189426D01*
G01D02*
X1290354D01*
G01X-4246Y-144926D02*
X1290354D01*
G01X-8246Y-93426D02*
G02I-12000J0D01*
G01X-13396D02*
G02I-6850J0D01*
G01X-20246Y-109426D02*
Y-77426D01*
G01X-4246Y-93426D02*
X-36246D01*
G01X-4246Y-109426D02*
X1290354D01*
G01X502854D02*
Y-189426D01*
G01X640354Y-109426D02*
Y-189426D01*
G01X755354Y-109426D02*
Y-189426D01*
G01X922854Y-109426D02*
Y-189426D01*
G01X1092854Y-109426D02*
Y-189426D01*
G01X1290354Y-109426D02*
Y-189426D01*
G01X1318354Y-93426D02*
G02I-12000J0D01*
G01X1313204D02*
G02I-6850J0D01*
G01X1306354Y-109426D02*
Y-77426D01*
G01X1322354Y-93426D02*
X1290354D01*
G54D19*
G01X-43308Y-5685D02*
G03X-29308Y-19685I14000J0D01*
G01X85820D02*
X-29308D01*
G01X0Y3937D02*
Y106969D01*
G01X636457Y0D02*
X3937D01*
G01X0Y3937D02*
G03X3937Y0I3937J0D01*
G01Y-7874D02*
X77283D01*
G01X-7874Y3937D02*
G03X3937Y-7874I11811J0D01*
G01X-7874Y50259D02*
Y3937D01*
G01X-43308Y-5685D02*
Y103032D01*
G01X0Y3937D02*
G03X3937Y0I3937J0D01*
G01X0Y3937D02*
G03X3937Y0I3937J0D01*
G01X636457D02*
X3937D01*
G01X636457D02*
X3937D01*
G01X0Y3937D02*
Y106969D01*
G01Y3937D02*
Y106969D01*
G01Y50259D02*
G03X-7874I-3937J0D01*
G01Y75460D02*
G03X0I3937J0D01*
G01X-7874Y103032D02*
Y75456D01*
G01X-43307Y286142D02*
Y116811D01*
G01D02*
X-37402Y110906D01*
G01D02*
X-3937D01*
G01X0Y106969D02*
G03X-3937Y110906I-3937J0D01*
G01X-43308Y103032D02*
X-7874D01*
G01X0Y106969D02*
G03X-3937Y110906I-3937J0D01*
G01X0Y106969D02*
G03X-3937Y110906I-3937J0D01*
G01X-37402D02*
X-3937D01*
G01X-37402D02*
X-3937D01*
G01X-41339Y114843D02*
X-37402Y110906D01*
G01X-43307Y116811D02*
X-37402Y110906D01*
G01X-43307Y286142D02*
Y116811D01*
G01Y360039D02*
Y300709D01*
G01X-37402Y292047D02*
X-43307Y286142D01*
G01Y300709D02*
X-37402Y294803D01*
G01Y292047D02*
X-1378D01*
G01X-37402Y294803D02*
X-1378D01*
G01Y292047D02*
G03Y294803I0J1378D01*
G01Y292047D02*
G03Y294803I0J1378D01*
G01Y292047D02*
G03Y294803I0J1378D01*
G01X-37402D02*
X-1378D01*
G01X-37402D02*
X-1378D01*
G01X-12598Y292047D02*
X-1378D01*
G01X-37402D02*
X-1378D01*
G01X-12598D02*
X-37402D01*
G01X-41339Y298740D02*
X-37402Y294803D01*
G01X-43307Y300709D02*
X-37402Y294803D01*
G01Y292047D02*
X-43307Y286142D01*
G01X-37402Y292047D02*
X-41339Y288110D01*
G01X-43307Y360039D02*
Y300709D01*
G01X-37402Y365945D02*
X-43307Y360039D01*
G01X0Y369882D02*
Y468504D01*
G01X-3937Y365945D02*
X-37402D01*
G01X-3937D02*
G03X0Y369882I0J3937D01*
G01X-43308Y373820D02*
Y583347D01*
G01X-43307Y373819D02*
X-43308Y373820D01*
G01X-7874Y373819D02*
X-43307D01*
G01X-7874Y401397D02*
Y373819D01*
G01X-3937Y365945D02*
G03X0Y369882I0J3937D01*
G01X-3937Y365945D02*
G03X0Y369882I0J3937D01*
G01X-3937Y365945D02*
X-37402D01*
G01X-3937D02*
X-37402D01*
G01X0Y369882D02*
Y468504D01*
G01Y369882D02*
Y468504D01*
G01X-37402Y365945D02*
X-43307Y360039D01*
G01X-37402Y365945D02*
X-41339Y362008D01*
G01X-7874Y426594D02*
Y530574D01*
G01Y426594D02*
G03X0I3937J0D01*
G01Y401397D02*
G03X-7874I-3937J0D01*
G01X3937Y472441D02*
X636457D01*
G01X3937D02*
G03X0Y468504I0J-3937D01*
G01Y484252D02*
G03X3937Y480315I3937J0D01*
G01X0Y484252D02*
G03X3937Y480315I3937J0D01*
G01X636457D02*
X3937D01*
G01X636457D02*
X3937D01*
G01X0Y484252D02*
Y587283D01*
G01Y484252D02*
Y587283D01*
G01X3937Y472441D02*
G03X0Y468504I0J-3937D01*
G01X3937Y472441D02*
G03X0Y468504I0J-3937D01*
G01X3937Y472441D02*
X636457D01*
G01X3937D02*
X636457D01*
G01X0Y530574D02*
G03X-7874I-3937J0D01*
G01Y555771D02*
G03X0I3937J0D01*
G01X-7874Y583347D02*
Y555771D01*
G01X-43308Y583347D02*
X-7874D01*
G01X0Y587283D02*
G03X-3937Y591220I-3937J0D01*
G01X0Y587283D02*
G03X-3937Y591220I-3937J0D01*
G01X-37402D02*
X-3937D01*
G01X-37402D02*
X-3937D01*
G01X-41339Y595157D02*
X-37402Y591220D01*
G01X-43307Y597126D02*
X-37402Y591220D01*
G01X-43307Y766457D02*
Y597126D01*
G01X-1378Y772362D02*
G03Y775118I0J1378D01*
G01Y772362D02*
G03Y775118I0J1378D01*
G01X-37402D02*
X-1378D01*
G01X-37402D02*
X-1378D01*
G01X-12598Y772362D02*
X-1378D01*
G01X-37402D02*
X-1378D01*
G01X-12598D02*
X-37402D01*
G01X-41339Y779055D02*
X-37402Y775118D01*
G01X-43307Y781024D02*
X-37402Y775118D01*
G01Y772362D02*
X-43307Y766457D01*
G01X-37402Y772362D02*
X-41339Y768425D01*
G01X-43307Y840354D02*
Y781024D01*
G01X-37402Y846260D02*
X-43307Y840354D01*
G01X-37402Y846260D02*
X-41339Y842323D01*
G01X0Y881711D02*
G03X-7874I-3937J0D01*
G01X-43308Y854134D02*
Y958441D01*
G01X-7874Y854134D02*
X-43308D01*
G01X-7874Y881712D02*
Y854134D01*
G01X-3937Y846260D02*
G03X0Y850197I0J3937D01*
G01X-3937Y846260D02*
G03X0Y850197I0J3937D01*
G01X-3937Y846260D02*
X-37402D01*
G01X-3937D02*
X-37402D01*
G01X0Y850197D02*
Y948819D01*
G01Y850197D02*
Y948819D01*
G01X3937Y960630D02*
G03X-7874Y948819I0J-11811D01*
G01Y906909D02*
Y948819D01*
G01Y906909D02*
G03X0I3937J0D01*
G01X-29308Y972441D02*
G03X-43308Y958441I0J-14000D01*
G01X3937Y952756D02*
G03X0Y948819I0J-3937D01*
G01X3937Y952756D02*
G03X0Y948819I0J-3937D01*
G01X3937Y952756D02*
X636457D01*
G01X3937D02*
X636457D01*
G01X3937Y960630D02*
X77283D01*
G01X-29308Y972441D02*
X1317968D01*
G01X121969Y-179426D02*
Y-161926D01*
G01X131139D02*
Y-179426D01*
G01Y-170676D02*
X121969D01*
G01X144054Y-179426D02*
X142744Y-179134D01*
X141434Y-177968D01*
X140560Y-175926D01*
X140124Y-173593D01*
X140560Y-171259D01*
X141434Y-169218D01*
X142744Y-168051D01*
X144054Y-167760D01*
X145364Y-168051D01*
X146674Y-169218D01*
X147547Y-171259D01*
X147766Y-173593D01*
X147547Y-175926D01*
X146674Y-177968D01*
X145364Y-179134D01*
X144054Y-179426D01*
G01X157842D02*
Y-167760D01*
G01Y-170676D02*
X158716Y-169218D01*
X160026Y-168051D01*
X161772Y-167760D01*
X163300Y-168051D01*
X164611Y-169218D01*
X165266Y-171259D01*
Y-179426D01*
G01X175779Y-171551D02*
X182766D01*
X182111Y-169509D01*
X181019Y-168343D01*
X179491Y-167760D01*
X177962Y-168051D01*
X176652Y-168926D01*
X175779Y-170968D01*
X175342Y-172718D01*
Y-174468D01*
X175779Y-176218D01*
X176871Y-177968D01*
X178181Y-179134D01*
X179709Y-179426D01*
X181237Y-178843D01*
X182766Y-177093D01*
G01X191969Y-184676D02*
X193279Y-185259D01*
X195026Y-184676D01*
X196117Y-183510D01*
X196991Y-182051D01*
X198300Y-177385D01*
X201139Y-167760D01*
G01X194152D02*
X198300Y-177385D01*
G01X233300Y-170093D02*
X234174Y-169218D01*
X234829Y-167760D01*
X235266Y-165717D01*
X234829Y-163968D01*
X233956Y-162801D01*
X232427Y-161926D01*
X226532D01*
Y-179426D01*
X233737D01*
X235266Y-178260D01*
X236139Y-176509D01*
X236576Y-174468D01*
X236139Y-172426D01*
X234829Y-170676D01*
X233300Y-170093D01*
X226532D01*
G01X252984Y-179426D02*
Y-167760D01*
G01Y-169801D02*
X252111Y-168635D01*
X250800Y-168051D01*
X249272Y-167760D01*
X247744Y-168343D01*
X246434Y-169509D01*
X245560Y-171259D01*
X245124Y-173593D01*
X245560Y-175926D01*
X246434Y-177676D01*
X247744Y-178843D01*
X249272Y-179426D01*
X250800Y-179134D01*
X252111Y-178260D01*
X252984Y-177093D01*
G01X270484Y-161926D02*
Y-179426D01*
G01Y-176802D02*
X269611Y-178260D01*
X268300Y-179134D01*
X266772Y-179426D01*
X265026Y-178843D01*
X263716Y-177385D01*
X262842Y-175635D01*
X262624Y-173593D01*
X262842Y-171551D01*
X263716Y-169801D01*
X265026Y-168343D01*
X266772Y-167760D01*
X268300Y-168051D01*
X269392Y-168635D01*
X270484Y-169801D01*
G01X280997Y-183801D02*
X282526Y-184968D01*
X284272Y-185259D01*
X285800Y-184968D01*
X287111Y-183510D01*
X287984Y-181468D01*
Y-167760D01*
G01Y-170093D02*
X287111Y-168926D01*
X285800Y-168051D01*
X284272Y-167760D01*
X282526Y-168343D01*
X281434Y-169509D01*
X280560Y-171551D01*
X280124Y-173593D01*
X280342Y-175343D01*
X281216Y-177385D01*
X282526Y-178843D01*
X284272Y-179426D01*
X285582Y-179134D01*
X287111Y-177968D01*
X287984Y-176802D01*
G01X298279Y-171551D02*
X305266D01*
X304611Y-169509D01*
X303519Y-168343D01*
X301991Y-167760D01*
X300462Y-168051D01*
X299152Y-168926D01*
X298279Y-170968D01*
X297842Y-172718D01*
Y-174468D01*
X298279Y-176218D01*
X299371Y-177968D01*
X300681Y-179134D01*
X302209Y-179426D01*
X303737Y-178843D01*
X305266Y-177093D01*
G01X315997Y-179426D02*
Y-167760D01*
G01Y-170093D02*
X317089Y-168926D01*
X318181Y-168051D01*
X319709Y-167760D01*
X320800Y-168051D01*
X322111Y-168926D01*
G01X349687Y-179426D02*
Y-161926D01*
X354927D01*
X356674Y-162801D01*
X357984Y-164843D01*
X358421Y-167176D01*
X357984Y-169509D01*
X356892Y-171259D01*
X354927Y-172135D01*
X349687D01*
G01X371554Y-161926D02*
Y-179426D01*
G01X366532Y-161926D02*
X376576D01*
G01X390800Y-170093D02*
X391674Y-169218D01*
X392329Y-167760D01*
X392766Y-165717D01*
X392329Y-163968D01*
X391456Y-162801D01*
X389927Y-161926D01*
X384032D01*
Y-179426D01*
X391237D01*
X392766Y-178260D01*
X393639Y-176509D01*
X394076Y-174468D01*
X393639Y-172426D01*
X392329Y-170676D01*
X390800Y-170093D01*
X384032D01*
G01X93694Y-19685D02*
G03X85820I-3937J0D01*
G01X93694D02*
X1317968D01*
G01X77283Y-7874D02*
G03Y0I0J3937D01*
G01X107993D02*
G03Y-7874I0J-3937D01*
G01D02*
X304843D01*
G01X77283Y472441D02*
G03Y480315I0J3937D01*
G01X107993D02*
G03Y472441I0J-3937D01*
G01X77283Y952756D02*
G03Y960630I0J3937D01*
G01X107993D02*
G03Y952756I0J-3937D01*
G01Y960630D02*
X304843D01*
G01X208377Y-134426D02*
Y-116926D01*
X214054Y-131509D01*
X219731Y-116926D01*
Y-134426D01*
G01X231554D02*
X230244Y-134134D01*
X228934Y-132968D01*
X228060Y-130926D01*
X227624Y-128593D01*
X228060Y-126259D01*
X228934Y-124218D01*
X230244Y-123051D01*
X231554Y-122760D01*
X232864Y-123051D01*
X234174Y-124218D01*
X235047Y-126259D01*
X235266Y-128593D01*
X235047Y-130926D01*
X234174Y-132968D01*
X232864Y-134134D01*
X231554Y-134426D01*
G01X252984Y-116926D02*
Y-134426D01*
G01Y-131802D02*
X252111Y-133260D01*
X250800Y-134134D01*
X249272Y-134426D01*
X247526Y-133843D01*
X246216Y-132385D01*
X245342Y-130635D01*
X245124Y-128593D01*
X245342Y-126551D01*
X246216Y-124801D01*
X247526Y-123343D01*
X249272Y-122760D01*
X250800Y-123051D01*
X251892Y-123635D01*
X252984Y-124801D01*
G01X263279Y-126551D02*
X270266D01*
X269611Y-124509D01*
X268519Y-123343D01*
X266991Y-122760D01*
X265462Y-123051D01*
X264152Y-123926D01*
X263279Y-125968D01*
X262842Y-127718D01*
Y-129468D01*
X263279Y-131218D01*
X264371Y-132968D01*
X265681Y-134134D01*
X267209Y-134426D01*
X268737Y-133843D01*
X270266Y-132093D01*
G01X284054Y-134426D02*
Y-116926D01*
G01X335552Y0D02*
G03Y-7874I0J-3937D01*
G01X304843D02*
G03Y0I0J3937D01*
G01X335552Y-7874D02*
X532402D01*
G01X304843Y472441D02*
G03Y480315I0J3937D01*
G01X335552D02*
G03Y472441I0J-3937D01*
G01Y960630D02*
G03Y952756I0J-3937D01*
G01X304843D02*
G03Y960630I0J3937D01*
G01X335552D02*
X532402D01*
G01X536554Y-179426D02*
Y-161926D01*
X533934Y-165426D01*
G01Y-179426D02*
X539174D01*
G01X556674D02*
Y-161926D01*
X548595Y-174468D01*
X559513D01*
G01X567406Y-172135D02*
X568934Y-170093D01*
X570244Y-168926D01*
X571991Y-168343D01*
X573519Y-168926D01*
X574611Y-170093D01*
X575484Y-171843D01*
X575702Y-173884D01*
X575484Y-175635D01*
X574611Y-177385D01*
X573300Y-178843D01*
X571772Y-179426D01*
X570026Y-178843D01*
X568497Y-177093D01*
X567624Y-174468D01*
X567406Y-171551D01*
X567842Y-167760D01*
X568497Y-165717D01*
X569589Y-163676D01*
X571117Y-162218D01*
X572646Y-161926D01*
X574174Y-162509D01*
X575266Y-163968D01*
G01X584906Y-164843D02*
X586216Y-163093D01*
X587744Y-162218D01*
X589491Y-161926D01*
X591674Y-162509D01*
X593202Y-163968D01*
X593639Y-165717D01*
X593421Y-167468D01*
X592547Y-168926D01*
X588181Y-171843D01*
X586216Y-173884D01*
X584906Y-176802D01*
X584469Y-179426D01*
X593639D01*
G01X602842Y-177385D02*
X604371Y-178843D01*
X606117Y-179426D01*
X607864Y-178843D01*
X609392Y-177093D01*
X610484Y-174468D01*
X610921Y-171843D01*
Y-168635D01*
X610484Y-166010D01*
X609392Y-163676D01*
X608082Y-162509D01*
X606554Y-161926D01*
X604807Y-162509D01*
X603497Y-163676D01*
X602624Y-165426D01*
X602187Y-167760D01*
X602624Y-169801D01*
X603716Y-171843D01*
X605026Y-173010D01*
X606554Y-173301D01*
X608300Y-172718D01*
X609611Y-171259D01*
X610921Y-168635D01*
G01X523437Y-134426D02*
Y-116926D01*
X528677D01*
X530424Y-117801D01*
X531734Y-119843D01*
X532171Y-122176D01*
X531734Y-124509D01*
X530642Y-126259D01*
X528677Y-127135D01*
X523437D01*
G01X550107Y-118385D02*
X548797Y-117509D01*
X547269Y-116926D01*
X545522D01*
X543557Y-117801D01*
X542029Y-119259D01*
X540937Y-121010D01*
X540064Y-123926D01*
X539845Y-126551D01*
X540282Y-129176D01*
X540937Y-130926D01*
X542247Y-132676D01*
X543776Y-133843D01*
X545304Y-134426D01*
X546832D01*
X548361Y-133843D01*
X549671Y-132968D01*
X550763Y-131802D01*
G01X564550Y-125093D02*
X565424Y-124218D01*
X566079Y-122760D01*
X566516Y-120717D01*
X566079Y-118968D01*
X565206Y-117801D01*
X563677Y-116926D01*
X557782D01*
Y-134426D01*
X564987D01*
X566516Y-133260D01*
X567389Y-131509D01*
X567826Y-129468D01*
X567389Y-127426D01*
X566079Y-125676D01*
X564550Y-125093D01*
X557782D01*
G01X573754Y-140259D02*
X586854D01*
G01X592782Y-134426D02*
Y-116926D01*
X602826Y-134426D01*
Y-116926D01*
G01X615304Y-134426D02*
X613557Y-134134D01*
X612029Y-132968D01*
X610719Y-131218D01*
X609845Y-129176D01*
X609409Y-126843D01*
Y-124509D01*
X609845Y-122176D01*
X610719Y-120134D01*
X612029Y-118385D01*
X613557Y-117218D01*
X615304Y-116926D01*
X617050Y-117218D01*
X618579Y-118385D01*
X619889Y-120134D01*
X620763Y-122176D01*
X621199Y-124509D01*
Y-126843D01*
X620763Y-129176D01*
X619889Y-131218D01*
X618579Y-132968D01*
X617050Y-134134D01*
X615304Y-134426D01*
G01X532402Y-7874D02*
G03Y0I0J3937D01*
G01X563111D02*
G03Y-7874I0J-3937D01*
G01D02*
X725552D01*
G01X627391Y353740D02*
X545906D01*
G01X627391Y378543D02*
X545906D01*
G01X541969Y357677D02*
Y374606D01*
G01Y357677D02*
G03X545906Y353740I3937J0D01*
G01Y378543D02*
G03X541969Y374606I0J-3937D01*
G01X545906Y378543D02*
G03X541969Y374606I0J-3937D01*
G01Y357677D02*
G03X545906Y353740I3937J0D01*
G01X541969Y357677D02*
G03X545906Y353740I3937J0D01*
G01Y378543D02*
G03X541969Y374606I0J-3937D01*
G01Y357677D02*
Y374606D01*
G01Y357677D02*
Y374606D01*
G01X627391Y378543D02*
X545906D01*
G01X627391D02*
X545906D01*
G01X627391Y353740D02*
X545906D01*
G01X627391D02*
X545906D01*
G01X532402Y472441D02*
G03Y480315I0J3937D01*
G01X563111D02*
G03Y472441I0J-3937D01*
G01X541969Y837992D02*
G03X545906Y834055I3937J0D01*
G01X541969Y837992D02*
G03X545906Y834055I3937J0D01*
G01X541969Y837992D02*
Y854921D01*
G01Y837992D02*
Y854921D01*
G01X627391Y834055D02*
X545906D01*
G01X627391D02*
X545906D01*
G01Y858858D02*
G03X541969Y854921I0J-3937D01*
G01X545906Y858858D02*
G03X541969Y854921I0J-3937D01*
G01X627391Y858858D02*
X545906D01*
G01X627391D02*
X545906D01*
G01X532402Y952756D02*
G03Y960630I0J3937D01*
G01X563111D02*
G03Y952756I0J-3937D01*
G01Y960630D02*
X725552D01*
G01X636457Y132035D02*
X624646D01*
G01X620709Y135972D02*
G03X622675Y132564I3937J0D01*
G01X622709Y132545D02*
G03X624646Y132035I1938J3427D01*
G01X622675Y132564D02*
G03X622709Y132545I1937J3427D01*
G01X622675Y132564D02*
G03X624646Y132035I1971J3409D01*
G01X620709Y135972D02*
G03X622675Y132564I3937J0D01*
G01X620709Y135972D02*
G03X622708Y132545I3937J0D01*
G01X620709Y135972D02*
Y312846D01*
G01Y135972D02*
Y312846D01*
G01X622675Y132564D02*
G03X624646Y132035I1971J3409D01*
G01X622708Y132545D02*
G03X624646Y132035I1938J3427D01*
G01X620709Y135972D02*
G03X622675Y132564I3937J0D01*
G01X620709Y135972D02*
G03X622708Y132545I3937J0D01*
G01X620709Y135972D02*
Y312846D01*
G01Y135972D02*
Y312846D01*
G01X636457Y132035D02*
X624646D01*
G01X636457D02*
X624646D01*
G01X636457Y316783D02*
X624646D01*
G01X622675Y316255D02*
G03X620709Y312846I1971J-3408D01*
G01X624646Y316783D02*
G03X622709Y316274I-1J-3937D01*
G01D02*
G03X622675Y316255I1904J-3446D01*
G01X624646Y316783D02*
G03X622675Y316255I-1J-3937D01*
G01D02*
G03X620709Y312846I1971J-3408D01*
G01X622708Y316274D02*
G03X620709Y312846I1938J-3427D01*
G01X624646Y316783D02*
G03X622675Y316255I-1J-3937D01*
G01X624646Y316783D02*
G03X622708Y316274I-2J-3937D01*
G01X622675Y316255D02*
G03X620709Y312846I1971J-3408D01*
G01X622708Y316274D02*
G03X620709Y312846I1938J-3427D01*
G01X636457Y316783D02*
X624646D01*
G01X636457D02*
X624646D01*
G01X620709Y312657D02*
Y311161D01*
G01X629575Y379204D02*
X638641Y385248D01*
G01Y347035D02*
X629575Y353079D01*
G01D02*
G03X627391Y353740I-2184J-3276D01*
G01Y378543D02*
G03X629575Y379204I0J3937D01*
G01X627391Y378543D02*
G03X629574Y379205I-2J3937D01*
G01X627391Y378543D02*
G03X629574Y379205I-2J3937D01*
G01Y353079D02*
G03X627391Y353740I-2184J-3276D01*
G01X629574Y353079D02*
G03X627391Y353740I-2184J-3276D01*
G01X638641Y347035D02*
X629574Y353079D01*
G01X638641Y347035D02*
X629574Y353079D01*
G01Y379204D02*
X638641Y385248D01*
G01X629574Y379204D02*
X638641Y385248D01*
G01X622675Y612879D02*
G03X624646Y612350I1971J3409D01*
G01X622708Y612860D02*
G03X624646Y612350I1938J3427D01*
G01X620709Y616287D02*
G03X622675Y612879I3937J0D01*
G01X620709Y616287D02*
G03X622708Y612860I3937J0D01*
G01X620709Y616287D02*
Y793161D01*
G01Y616287D02*
Y793161D01*
G01X636457Y612350D02*
X624646D01*
G01X636457D02*
X624646D01*
G01Y797098D02*
G03X622675Y796570I-1J-3937D01*
G01X624646Y797098D02*
G03X622708Y796589I-2J-3937D01*
G01X622675Y796570D02*
G03X620709Y793161I1971J-3408D01*
G01X622708Y796589D02*
G03X620709Y793161I1938J-3427D01*
G01X636457Y797098D02*
X624646D01*
G01X636457D02*
X624646D01*
G01X629574Y833394D02*
G03X627391Y834055I-2184J-3276D01*
G01X629574Y833394D02*
G03X627391Y834055I-2184J-3276D01*
G01X638641Y827350D02*
X629574Y833394D01*
G01X638641Y827350D02*
X629574Y833394D01*
G01X627391Y858858D02*
G03X629574Y859520I-2J3937D01*
G01X627391Y858858D02*
G03X629574Y859520I-2J3937D01*
G01D02*
X638641Y865563D01*
G01X629574Y859520D02*
X638641Y865563D01*
G01X689104Y-179426D02*
Y-161926D01*
X686484Y-165426D01*
G01Y-179426D02*
X691724D01*
G01X701145D02*
X706604Y-161926D01*
X712063Y-179426D01*
G01X710097Y-173301D02*
X703110D01*
G01X666145Y-116926D02*
X671604Y-134426D01*
X677063Y-116926D01*
G01X693471Y-134426D02*
X684737D01*
Y-116926D01*
X693471D01*
G01X689977Y-125384D02*
X684737D01*
G01X702237Y-134426D02*
Y-116926D01*
X707696D01*
X709442Y-117801D01*
X710534Y-118968D01*
X710971Y-121301D01*
X710534Y-123635D01*
X709224Y-125093D01*
X707696Y-125968D01*
X702237D01*
G01X707696D02*
X710971Y-134426D01*
G01X724104Y-135009D02*
X723667Y-134718D01*
Y-134134D01*
X724104Y-133843D01*
X724541Y-134134D01*
Y-134718D01*
X724104Y-135009D01*
G01X640394Y128098D02*
Y3937D01*
G01X636457Y0D02*
G03X640394Y3937I0J3937D01*
G01Y128098D02*
Y3937D01*
G01Y128098D02*
Y3937D01*
G01X648267Y34437D02*
G03X640393I-3937J0D01*
G01X648266Y3937D02*
G03X652203Y0I3937J0D01*
G01X648266Y3937D02*
G03X652203Y0I3937J0D01*
G01X648266Y3937D02*
Y83917D01*
G01Y3937D02*
Y83917D01*
G01X1284723Y0D02*
X652203D01*
G01X1284723D02*
X652203D01*
G01X636457D02*
G03X640394Y3937I0J3937D01*
G01X636457Y0D02*
G03X640394Y3937I0J3937D01*
G01Y112350D02*
Y3937D01*
G01Y112350D02*
Y3937D01*
G01X640393Y65146D02*
G03X648267I3937J0D01*
G01X650019Y87193D02*
G03X648266Y83917I2185J-3276D01*
G01X661269Y93898D02*
G03X659085Y93237I0J-3937D01*
G01X661269Y93898D02*
G03X659085Y93237I0J-3937D01*
G01X650019Y87193D02*
G03X648266Y83917I2185J-3276D01*
G01X661269Y93898D02*
X742754D01*
G01X661269D02*
X742754D01*
G01X659085Y93237D02*
X650019Y87193D01*
G01X659085Y93237D02*
X650019Y87193D01*
G01X640394Y128098D02*
G03X636457Y132035I-3937J0D01*
G01X664014Y155657D02*
G03X665985Y156186I0J3938D01*
G01X652203Y155657D02*
G03X648266Y151720I0J-3937D01*
G01X652203Y155657D02*
G03X648266Y151720I0J-3937D01*
G01X664014Y155657D02*
G03X665952Y156167I0J3937D01*
G01X665985Y156186D02*
G03X667951Y159594I-1971J3408D01*
G01X665952Y156167D02*
G03X667951Y159594I-1938J3427D01*
G01X648266Y128682D02*
Y151720D01*
G01Y128682D02*
Y151720D01*
G01X667951Y336469D02*
Y159594D01*
G01Y336469D02*
Y159594D01*
G01X652203Y155657D02*
X664014D01*
G01X652203D02*
X664014D01*
G01X640394Y128098D02*
G03X636457Y132035I-3937J0D01*
G01X640394Y128098D02*
G03X636457Y132035I-3937J0D01*
G01X659085Y119362D02*
G03X661269Y118701I2184J3276D01*
G01X648266Y128682D02*
G03X650019Y125406I3937J0D01*
G01X648266Y128682D02*
G03X650019Y125406I3937J0D01*
G01X659085Y119362D02*
G03X661269Y118701I2184J3276D01*
G01X650019Y125406D02*
X659085Y119362D01*
G01X650019Y125406D02*
X659085Y119362D01*
G01X661269Y118701D02*
X742754D01*
G01X661269D02*
X742754D01*
G01X640394Y343759D02*
Y320720D01*
G01X636457Y316783D02*
G03X640394Y320720I0J3937D01*
G01X636457Y316783D02*
G03X640394Y320720I0J3937D01*
G01X636457Y316783D02*
G03X640394Y320720I0J3937D01*
G01Y343759D02*
Y320720D01*
G01Y343759D02*
Y320720D01*
G01Y388524D02*
Y421048D01*
G01Y343759D02*
G03X638641Y347035I-3937J0D01*
G01Y385248D02*
G03X640394Y388524I-2184J3276D01*
G01X665985Y339877D02*
G03X664014Y340406I-1971J-3409D01*
G01X648266Y344343D02*
G03X652203Y340406I3937J0D01*
G01X665952Y339896D02*
G03X664014Y340406I-1938J-3427D01*
G01X648266Y344343D02*
G03X652203Y340406I3937J0D01*
G01X667951Y336469D02*
G03X665985Y339877I-3937J0D01*
G01X667951Y336469D02*
G03X665952Y339896I-3937J0D01*
G01X648266Y344343D02*
Y468504D01*
G01Y344343D02*
Y468504D01*
G01X652203Y340406D02*
X664014D01*
G01X652203D02*
X664014D01*
G01X648266Y360091D02*
Y468504D01*
G01Y360091D02*
Y468504D01*
G01X638641Y385248D02*
G03X640394Y388524I-2185J3276D01*
G01X638641Y385248D02*
G03X640394Y388524I-2185J3276D01*
G01Y343759D02*
G03X638641Y347035I-3937J0D01*
G01X640394Y343759D02*
G03X638641Y347035I-3937J0D01*
G01X640394Y468504D02*
Y388524D01*
G01Y468504D02*
Y388524D01*
G01Y421048D02*
Y445094D01*
G01D02*
Y468504D01*
G01X640393Y438004D02*
G03X648267I3937J0D01*
G01Y407295D02*
G03X640393I-3937J0D01*
G01X640394Y468504D02*
G03X636457Y472441I-3937J0D01*
G01X640394Y608413D02*
Y484252D01*
G01Y608413D02*
Y484252D01*
G01X652203Y472441D02*
G03X648266Y468504I0J-3937D01*
G01X652203Y472441D02*
G03X648266Y468504I0J-3937D01*
G01X652203Y472441D02*
X1284723D01*
G01X652203D02*
X1284723D01*
G01X648266Y484252D02*
G03X652203Y480315I3937J0D01*
G01X648266Y484252D02*
G03X652203Y480315I3937J0D01*
G01X648266Y484252D02*
Y564231D01*
G01Y484252D02*
Y564231D01*
G01X1284723Y480315D02*
X652203D01*
G01X1284723D02*
X652203D01*
G01X636457D02*
G03X640394Y484252I0J3937D01*
G01X636457Y480315D02*
G03X640394Y484252I0J3937D01*
G01Y592665D02*
Y484252D01*
G01Y592665D02*
Y484252D01*
G01Y468504D02*
G03X636457Y472441I-3937J0D01*
G01X640394Y468504D02*
G03X636457Y472441I-3937J0D01*
G01X648267Y514753D02*
G03X640393I-3937J0D01*
G01Y545462D02*
G03X648267I3937J0D01*
G01X648266Y608997D02*
Y632035D01*
G01Y608997D02*
Y632035D01*
G01X640394Y608413D02*
G03X636457Y612350I-3937J0D01*
G01X640394Y608413D02*
G03X636457Y612350I-3937J0D01*
G01X650019Y567507D02*
G03X648266Y564231I2184J-3276D01*
G01X661269Y574213D02*
G03X659085Y573552I0J-3937D01*
G01X661269Y574213D02*
G03X659085Y573552I0J-3937D01*
G01X650019Y567507D02*
G03X648266Y564231I2184J-3276D01*
G01X659085Y599677D02*
G03X661269Y599016I2184J3276D01*
G01X648266Y608997D02*
G03X650019Y605721I3937J0D01*
G01X648266Y608997D02*
G03X650019Y605721I3937J0D01*
G01X659085Y599677D02*
G03X661269Y599016I2184J3276D01*
G01X650019Y605721D02*
X659085Y599677D01*
G01X650019Y605721D02*
X659085Y599677D01*
G01X661269Y574213D02*
X742754D01*
G01X661269D02*
X742754D01*
G01X661269Y599016D02*
X742754D01*
G01X661269D02*
X742754D01*
G01X659085Y573552D02*
X650019Y567507D01*
G01X659085Y573552D02*
X650019Y567507D01*
G01X664014Y635972D02*
G03X665985Y636501I0J3938D01*
G01X652203Y635972D02*
G03X648266Y632035I0J-3937D01*
G01X652203Y635972D02*
G03X648266Y632035I0J-3937D01*
G01X664014Y635972D02*
G03X665952Y636482I0J3937D01*
G01X665985Y636501D02*
G03X667951Y639909I-1971J3408D01*
G01X665952Y636482D02*
G03X667951Y639909I-1938J3427D01*
G01Y816783D02*
Y639909D01*
G01Y816783D02*
Y639909D01*
G01X652203Y635972D02*
X664014D01*
G01X652203D02*
X664014D01*
G01X665985Y820192D02*
G03X664014Y820720I-1970J-3409D01*
G01X648266Y824657D02*
G03X652203Y820720I3937J0D01*
G01X665952Y820211D02*
G03X664014Y820720I-1936J-3428D01*
G01X648266Y824657D02*
G03X652203Y820720I3937J0D01*
G01X667951Y816783D02*
G03X665985Y820192I-3937J1D01*
G01X667951Y816783D02*
G03X665952Y820211I-3937J1D01*
G01X648266Y824657D02*
Y948819D01*
G01Y824657D02*
Y948819D01*
G01X652203Y820720D02*
X664014D01*
G01X652203D02*
X664014D01*
G01X636457Y797098D02*
G03X640394Y801035I0J3937D01*
G01X636457Y797098D02*
G03X640394Y801035I0J3937D01*
G01Y824074D02*
Y801035D01*
G01Y824074D02*
Y801035D01*
G01X648266Y840406D02*
Y948819D01*
G01Y840406D02*
Y948819D01*
G01X640394Y824074D02*
G03X638641Y827350I-3938J0D01*
G01X640394Y824074D02*
G03X638641Y827350I-3938J0D01*
G01X648267Y887611D02*
G03X640393I-3937J0D01*
G01X638641Y865563D02*
G03X640394Y868839I-2185J3276D01*
G01X638641Y865563D02*
G03X640394Y868839I-2185J3276D01*
G01Y948819D02*
Y868839D01*
G01Y948819D02*
Y868839D01*
G01X640393Y918320D02*
G03X648267I3937J0D01*
G01X652203Y952756D02*
G03X648266Y948819I0J-3937D01*
G01X652203Y952756D02*
G03X648266Y948819I0J-3937D01*
G01X652203Y952756D02*
X1284723D01*
G01X652203D02*
X1284723D01*
G01X640394Y948819D02*
G03X636457Y952756I-3937J0D01*
G01X640394Y948819D02*
G03X636457Y952756I-3937J0D01*
G01X725552Y-7874D02*
G03Y0I0J3937D01*
G01X742754Y93898D02*
G03X746691Y97835I0J3937D01*
G01X742754Y93898D02*
G03X746691Y97835I0J3937D01*
G01Y114764D02*
Y97835D01*
G01Y114764D02*
Y97835D01*
G01Y114764D02*
G03X742754Y118701I-3937J0D01*
G01X746691Y114764D02*
G03X742754Y118701I-3937J0D01*
G01X725552Y472441D02*
G03Y480315I0J3937D01*
G01X742754Y574213D02*
G03X746691Y578150I0J3937D01*
G01Y595079D02*
G03X742754Y599016I-3937J0D01*
G01X746691Y595079D02*
G03X742754Y599016I-3937J0D01*
G01Y574213D02*
G03X746691Y578150I0J3937D01*
G01Y595079D02*
Y578150D01*
G01Y595079D02*
Y578150D01*
G01X725552Y952756D02*
G03Y960630I0J3937D01*
G01X799251Y-179426D02*
Y-161926D01*
X803617D01*
X805364Y-162801D01*
X806674Y-163968D01*
X807766Y-165717D01*
X808639Y-167760D01*
X808857Y-170676D01*
X808639Y-173593D01*
X807766Y-175635D01*
X806674Y-177385D01*
X805364Y-178551D01*
X803617Y-179426D01*
X799251D01*
G01X817187D02*
Y-161926D01*
X822646D01*
X824392Y-162801D01*
X825484Y-163968D01*
X825921Y-166301D01*
X825484Y-168635D01*
X824174Y-170093D01*
X822646Y-170968D01*
X817187D01*
G01X822646D02*
X825921Y-179426D01*
G01X836434Y-161926D02*
X841674D01*
G01X839054D02*
Y-179426D01*
G01X836434D02*
X841674D01*
G01X852187Y-161926D02*
Y-179426D01*
X860921D01*
G01X869687Y-161926D02*
Y-179426D01*
X878421D01*
G01X790937Y-116926D02*
Y-134426D01*
X799671D01*
G01X816734D02*
Y-122760D01*
G01Y-124801D02*
X815861Y-123635D01*
X814550Y-123051D01*
X813022Y-122760D01*
X811494Y-123343D01*
X810184Y-124509D01*
X809310Y-126259D01*
X808874Y-128593D01*
X809310Y-130926D01*
X810184Y-132676D01*
X811494Y-133843D01*
X813022Y-134426D01*
X814550Y-134134D01*
X815861Y-133260D01*
X816734Y-132093D01*
G01X825719Y-139676D02*
X827029Y-140259D01*
X828776Y-139676D01*
X829867Y-138510D01*
X830741Y-137051D01*
X832050Y-132385D01*
X834889Y-122760D01*
G01X827902D02*
X832050Y-132385D01*
G01X844529Y-126551D02*
X851516D01*
X850861Y-124509D01*
X849769Y-123343D01*
X848241Y-122760D01*
X846712Y-123051D01*
X845402Y-123926D01*
X844529Y-125968D01*
X844092Y-127718D01*
Y-129468D01*
X844529Y-131218D01*
X845621Y-132968D01*
X846931Y-134134D01*
X848459Y-134426D01*
X849987Y-133843D01*
X851516Y-132093D01*
G01X862247Y-134426D02*
Y-122760D01*
G01Y-125093D02*
X863339Y-123926D01*
X864431Y-123051D01*
X865959Y-122760D01*
X867050Y-123051D01*
X868361Y-123926D01*
G01X879529Y-132385D02*
X880621Y-133551D01*
X882149Y-134426D01*
X883459D01*
X884769Y-133843D01*
X885642Y-132968D01*
X886079Y-131802D01*
X885861Y-130051D01*
X884987Y-129176D01*
X881057Y-127426D01*
X880184Y-125384D01*
X880621Y-123926D01*
X881494Y-123051D01*
X882804Y-122760D01*
X884114Y-123051D01*
X885424Y-123926D01*
G01X953111Y-7874D02*
X756261D01*
G01Y0D02*
G03Y-7874I0J-3937D01*
G01Y480315D02*
G03Y472441I0J-3937D01*
G01Y960630D02*
G03Y952756I0J-3937D01*
G01X953111Y960630D02*
X756261D01*
G01X924737Y-175926D02*
X925829Y-177676D01*
X927139Y-178843D01*
X928667Y-179426D01*
X930414Y-178843D01*
X931724Y-177676D01*
X933034Y-175926D01*
X933471Y-173593D01*
Y-161926D01*
G01X946604Y-179426D02*
X944857Y-179134D01*
X943329Y-177968D01*
X942019Y-176218D01*
X941145Y-174176D01*
X940709Y-171843D01*
Y-169509D01*
X941145Y-167176D01*
X942019Y-165134D01*
X943329Y-163385D01*
X944857Y-162218D01*
X946604Y-161926D01*
X948350Y-162218D01*
X949879Y-163385D01*
X951189Y-165134D01*
X952063Y-167176D01*
X952499Y-169509D01*
Y-171843D01*
X952063Y-174176D01*
X951189Y-176218D01*
X949879Y-177968D01*
X948350Y-179134D01*
X946604Y-179426D01*
G01X959519Y-177093D02*
X961266Y-178551D01*
X963231Y-179426D01*
X964977D01*
X966724Y-178551D01*
X968034Y-177093D01*
X968689Y-175051D01*
X968252Y-173010D01*
X967161Y-171259D01*
X965196Y-170093D01*
X962576Y-169509D01*
X961047Y-168343D01*
X960392Y-166301D01*
X960829Y-164259D01*
X961921Y-162801D01*
X963449Y-161926D01*
X964977D01*
X966506Y-162509D01*
X967816Y-163968D01*
G01X985971Y-179426D02*
X977237D01*
Y-161926D01*
X985971D01*
G01X982477Y-170384D02*
X977237D01*
G01X994737Y-179426D02*
Y-161926D01*
X999977D01*
X1001724Y-162801D01*
X1003034Y-164843D01*
X1003471Y-167176D01*
X1003034Y-169509D01*
X1001942Y-171259D01*
X999977Y-172135D01*
X994737D01*
G01X1012019Y-179426D02*
Y-161926D01*
G01X1021189D02*
Y-179426D01*
G01Y-170676D02*
X1012019D01*
G01X1047237Y-161926D02*
Y-179426D01*
X1055971D01*
G01X1063645D02*
X1069104Y-161926D01*
X1074563Y-179426D01*
G01X1072597Y-173301D02*
X1065610D01*
G01X1081801Y-161926D02*
Y-174468D01*
X1082674Y-177093D01*
X1084421Y-178843D01*
X1086604Y-179426D01*
X1088787Y-178843D01*
X1090534Y-177093D01*
X1091407Y-174468D01*
Y-161926D01*
G01X941801Y-134426D02*
Y-116926D01*
X946167D01*
X947914Y-117801D01*
X949224Y-118968D01*
X950316Y-120717D01*
X951189Y-122760D01*
X951407Y-125676D01*
X951189Y-128593D01*
X950316Y-130635D01*
X949224Y-132385D01*
X947914Y-133551D01*
X946167Y-134426D01*
X941801D01*
G01X960829Y-126551D02*
X967816D01*
X967161Y-124509D01*
X966069Y-123343D01*
X964541Y-122760D01*
X963012Y-123051D01*
X961702Y-123926D01*
X960829Y-125968D01*
X960392Y-127718D01*
Y-129468D01*
X960829Y-131218D01*
X961921Y-132968D01*
X963231Y-134134D01*
X964759Y-134426D01*
X966287Y-133843D01*
X967816Y-132093D01*
G01X978329Y-132385D02*
X979421Y-133551D01*
X980949Y-134426D01*
X982259D01*
X983569Y-133843D01*
X984442Y-132968D01*
X984879Y-131802D01*
X984661Y-130051D01*
X983787Y-129176D01*
X979857Y-127426D01*
X978984Y-125384D01*
X979421Y-123926D01*
X980294Y-123051D01*
X981604Y-122760D01*
X982914Y-123051D01*
X984224Y-123926D01*
G01X999104Y-122760D02*
Y-134426D01*
G01Y-118093D02*
X998667Y-117801D01*
Y-117218D01*
X999104Y-116926D01*
X999541Y-117218D01*
Y-117801D01*
X999104Y-118093D01*
G01X1013547Y-138801D02*
X1015076Y-139968D01*
X1016822Y-140259D01*
X1018350Y-139968D01*
X1019661Y-138510D01*
X1020534Y-136468D01*
Y-122760D01*
G01Y-125093D02*
X1019661Y-123926D01*
X1018350Y-123051D01*
X1016822Y-122760D01*
X1015076Y-123343D01*
X1013984Y-124509D01*
X1013110Y-126551D01*
X1012674Y-128593D01*
X1012892Y-130343D01*
X1013766Y-132385D01*
X1015076Y-133843D01*
X1016822Y-134426D01*
X1018132Y-134134D01*
X1019661Y-132968D01*
X1020534Y-131802D01*
G01X1030392Y-134426D02*
Y-122760D01*
G01Y-125676D02*
X1031266Y-124218D01*
X1032576Y-123051D01*
X1034322Y-122760D01*
X1035850Y-123051D01*
X1037161Y-124218D01*
X1037816Y-126259D01*
Y-134426D01*
G01X1048329Y-126551D02*
X1055316D01*
X1054661Y-124509D01*
X1053569Y-123343D01*
X1052041Y-122760D01*
X1050512Y-123051D01*
X1049202Y-123926D01*
X1048329Y-125968D01*
X1047892Y-127718D01*
Y-129468D01*
X1048329Y-131218D01*
X1049421Y-132968D01*
X1050731Y-134134D01*
X1052259Y-134426D01*
X1053787Y-133843D01*
X1055316Y-132093D01*
G01X1066047Y-134426D02*
Y-122760D01*
G01Y-125093D02*
X1067139Y-123926D01*
X1068231Y-123051D01*
X1069759Y-122760D01*
X1070850Y-123051D01*
X1072161Y-123926D01*
G01X953111Y-7874D02*
G03Y0I0J3937D01*
G01Y472441D02*
G03Y480315I0J3937D01*
G01Y952756D02*
G03Y960630I0J3937D01*
G01X1180670Y-7874D02*
X983820D01*
G01Y0D02*
G03Y-7874I0J-3937D01*
G01Y480315D02*
G03Y472441I0J-3937D01*
G01Y960630D02*
G03Y952756I0J-3937D01*
G01X1180670Y960630D02*
X983820D01*
G01X1112804Y-179426D02*
Y-161926D01*
X1110184Y-165426D01*
G01Y-179426D02*
X1115424D01*
G01X1130304D02*
Y-161926D01*
X1127684Y-165426D01*
G01Y-179426D02*
X1132924D01*
G01X1143874Y-180009D02*
X1151734Y-161926D01*
G01X1161156Y-164843D02*
X1162466Y-163093D01*
X1163994Y-162218D01*
X1165741Y-161926D01*
X1167924Y-162509D01*
X1169452Y-163968D01*
X1169889Y-165717D01*
X1169671Y-167468D01*
X1168797Y-168926D01*
X1164431Y-171843D01*
X1162466Y-173884D01*
X1161156Y-176802D01*
X1160719Y-179426D01*
X1169889D01*
G01X1178001Y-176802D02*
X1179310Y-178260D01*
X1180839Y-179134D01*
X1182804Y-179426D01*
X1184769Y-178843D01*
X1186297Y-177676D01*
X1187389Y-175635D01*
X1187607Y-173301D01*
X1187171Y-170968D01*
X1186079Y-169509D01*
X1184550Y-168343D01*
X1183022Y-168051D01*
X1181494Y-168343D01*
X1179529Y-169509D01*
X1180184Y-161926D01*
X1186079D01*
G01X1196374Y-180009D02*
X1204234Y-161926D01*
G01X1213656Y-164843D02*
X1214966Y-163093D01*
X1216494Y-162218D01*
X1218241Y-161926D01*
X1220424Y-162509D01*
X1221952Y-163968D01*
X1222389Y-165717D01*
X1222171Y-167468D01*
X1221297Y-168926D01*
X1216931Y-171843D01*
X1214966Y-173884D01*
X1213656Y-176802D01*
X1213219Y-179426D01*
X1222389D01*
G01X1235304Y-161926D02*
X1233557Y-162509D01*
X1232247Y-163968D01*
X1231374Y-165717D01*
X1230719Y-168051D01*
X1230501Y-170676D01*
X1230719Y-173301D01*
X1231374Y-175635D01*
X1232247Y-177385D01*
X1233557Y-178843D01*
X1235304Y-179426D01*
X1237050Y-178843D01*
X1238361Y-177385D01*
X1239234Y-175635D01*
X1239889Y-173301D01*
X1240107Y-170676D01*
X1239889Y-168051D01*
X1239234Y-165717D01*
X1238361Y-163968D01*
X1237050Y-162509D01*
X1235304Y-161926D01*
G01X1252804Y-179426D02*
Y-161926D01*
X1250184Y-165426D01*
G01Y-179426D02*
X1255424D01*
G01X1272924D02*
Y-161926D01*
X1264845Y-174468D01*
X1275763D01*
G01X1160501Y-134426D02*
Y-116926D01*
X1164867D01*
X1166614Y-117801D01*
X1167924Y-118968D01*
X1169016Y-120717D01*
X1169889Y-122760D01*
X1170107Y-125676D01*
X1169889Y-128593D01*
X1169016Y-130635D01*
X1167924Y-132385D01*
X1166614Y-133551D01*
X1164867Y-134426D01*
X1160501D01*
G01X1186734D02*
Y-122760D01*
G01Y-124801D02*
X1185861Y-123635D01*
X1184550Y-123051D01*
X1183022Y-122760D01*
X1181494Y-123343D01*
X1180184Y-124509D01*
X1179310Y-126259D01*
X1178874Y-128593D01*
X1179310Y-130926D01*
X1180184Y-132676D01*
X1181494Y-133843D01*
X1183022Y-134426D01*
X1184550Y-134134D01*
X1185861Y-133260D01*
X1186734Y-132093D01*
G01X1200304Y-116926D02*
Y-134426D01*
G01X1197247Y-122760D02*
X1203361D01*
G01X1214529Y-126551D02*
X1221516D01*
X1220861Y-124509D01*
X1219769Y-123343D01*
X1218241Y-122760D01*
X1216712Y-123051D01*
X1215402Y-123926D01*
X1214529Y-125968D01*
X1214092Y-127718D01*
Y-129468D01*
X1214529Y-131218D01*
X1215621Y-132968D01*
X1216931Y-134134D01*
X1218459Y-134426D01*
X1219987Y-133843D01*
X1221516Y-132093D01*
G01X1180670Y-7874D02*
G03Y0I0J3937D01*
G01Y472441D02*
G03Y480315I0J3937D01*
G01Y952756D02*
G03Y960630I0J3937D01*
G01X1211380Y0D02*
G03Y-7874I0J-3937D01*
G01D02*
X1284723D01*
G01X1211380Y480315D02*
G03Y472441I0J-3937D01*
G01Y960630D02*
G03Y952756I0J-3937D01*
G01Y960630D02*
X1284723D01*
G01X1317968Y-19685D02*
G03X1331968Y-5685I0J14000D01*
G01X1296534Y45847D02*
G03X1288660I-3937J0D01*
G01X1296534Y3937D02*
Y45847D01*
G01X1284723Y-7874D02*
G03X1296534Y3937I0J11811D01*
G01X1284723Y0D02*
G03X1288660Y3937I0J3937D01*
G01X1284723Y0D02*
G03X1288660Y3937I0J3937D01*
G01Y102559D02*
Y3937D01*
G01Y102559D02*
Y3937D01*
G01Y71044D02*
G03X1296534I3937J0D01*
G01Y98622D02*
Y71044D01*
G01X1331968Y98622D02*
X1296534D01*
G01X1292597Y106496D02*
G03X1288660Y102559I0J-3937D01*
G01X1292597Y106496D02*
G03X1288660Y102559I0J-3937D01*
G01X1292597Y106496D02*
X1326061D01*
G01X1292597D02*
X1326061D01*
G01X1290038Y180394D02*
G03Y177638I0J-1378D01*
G01Y180394D02*
G03Y177638I0J-1378D01*
G01X1326061D02*
X1290038D01*
G01X1326061D02*
X1290038D01*
G01X1301258Y180394D02*
X1290038D01*
G01X1326061D02*
X1290038D01*
G01X1301258D02*
X1326061D01*
G01X1296534Y369409D02*
Y396985D01*
G01X1331968Y369409D02*
X1296534D01*
G01X1288660Y365472D02*
G03X1292597Y361535I3937J0D01*
G01X1288660Y365472D02*
G03X1292597Y361535I3937J0D01*
G01X1326061D02*
X1292597D01*
G01X1326061D02*
X1292597D01*
G01X1288660Y468504D02*
Y365472D01*
G01Y468504D02*
Y365472D01*
G01Y422182D02*
G03X1296534I3937J0D01*
G01Y526162D02*
Y422182D01*
G01Y396985D02*
G03X1288660I-3937J0D01*
G01Y468504D02*
G03X1284723Y472441I-3937J0D01*
G01X1288660Y468504D02*
G03X1284723Y472441I-3937J0D01*
G01Y480315D02*
G03X1288660Y484252I0J3937D01*
G01X1284723Y480315D02*
G03X1288660Y484252I0J3937D01*
G01Y582874D02*
Y484252D01*
G01Y582874D02*
Y484252D01*
G01X1296534Y526162D02*
G03X1288660I-3937J0D01*
G01Y551359D02*
G03X1296534I3937J0D01*
G01Y578937D02*
Y551359D01*
G01X1331968Y578937D02*
X1296534D01*
G01X1292597Y586811D02*
G03X1288660Y582874I0J-3937D01*
G01X1292597Y586811D02*
G03X1288660Y582874I0J-3937D01*
G01X1292597Y586811D02*
X1326061D01*
G01X1292597D02*
X1326061D01*
G01X1290038Y660709D02*
G03Y657953I0J-1378D01*
G01Y660709D02*
G03Y657953I0J-1378D01*
G01X1326061D02*
X1290038D01*
G01X1326061D02*
X1290038D01*
G01X1301258Y660709D02*
X1290038D01*
G01X1326061D02*
X1290038D01*
G01X1301258D02*
X1326061D01*
G01X1288660Y845787D02*
G03X1292597Y841850I3937J0D01*
G01X1288660Y845787D02*
G03X1292597Y841850I3937J0D01*
G01X1326061D02*
X1292597D01*
G01X1326061D02*
X1292597D01*
G01X1331968Y849724D02*
X1296534D01*
G01X1288660Y902497D02*
G03X1296534I3937J0D01*
G01Y948819D02*
Y902497D01*
G01Y877296D02*
G03X1288660I-3937J0D01*
G01X1296534Y849724D02*
Y877300D01*
G01X1288660Y948819D02*
Y845787D01*
G01Y948819D02*
Y845787D01*
G01X1296534Y948819D02*
G03X1284723Y960630I-11811J0D01*
G01X1288660Y948819D02*
G03X1284723Y952756I-3937J0D01*
G01X1288660Y948819D02*
G03X1284723Y952756I-3937J0D01*
G01X1331968Y958441D02*
G03X1317968Y972441I-14000J0D01*
G01X1331968Y-5685D02*
Y98622D01*
G01X1326061Y106496D02*
X1331967Y112402D01*
G01X1326061Y106496D02*
X1329998Y110433D01*
G01X1331967Y112402D02*
Y171732D01*
G01X1329998Y173701D02*
X1326061Y177638D01*
G01X1331967Y171732D02*
X1326061Y177638D01*
G01Y180394D02*
X1331967Y186299D01*
G01X1326061Y180394D02*
X1329998Y184331D01*
G01X1331967Y186299D02*
Y355630D01*
G01X1331968Y578937D02*
Y369409D01*
G01X1329998Y357598D02*
X1326061Y361535D01*
G01X1331967Y355630D02*
X1326061Y361535D01*
G01Y586811D02*
X1331967Y592717D01*
G01X1326061Y586811D02*
X1329998Y590748D01*
G01X1331967Y592717D02*
Y652047D01*
G01X1329998Y654016D02*
X1326061Y657953D01*
G01X1331967Y652047D02*
X1326061Y657953D01*
G01Y660709D02*
X1331967Y666614D01*
G01X1326061Y660709D02*
X1329998Y664646D01*
G01X1331967Y666614D02*
Y835945D01*
G01X1329998Y837913D02*
X1326061Y841850D01*
G01X1331967Y835945D02*
X1326061Y841850D01*
G01X1331968Y958441D02*
Y849724D01*
G01X1409585Y41500D02*
Y54000D01*
X1416715Y41500D01*
Y54000D01*
G01X1425550Y41500D02*
X1424620Y41708D01*
X1423690Y42541D01*
X1423070Y44000D01*
X1422760Y45667D01*
X1423070Y47333D01*
X1423690Y48792D01*
X1424620Y49625D01*
X1425550Y49833D01*
X1426480Y49625D01*
X1427410Y48792D01*
X1428030Y47333D01*
X1428185Y45667D01*
X1428030Y44000D01*
X1427410Y42541D01*
X1426480Y41708D01*
X1425550Y41500D01*
G01X1437950Y54000D02*
Y41500D01*
G01X1435780Y49833D02*
X1440120D01*
G01X1448025Y47125D02*
X1452985D01*
X1452520Y48583D01*
X1451745Y49417D01*
X1450660Y49833D01*
X1449575Y49625D01*
X1448645Y49000D01*
X1448025Y47542D01*
X1447715Y46291D01*
Y45042D01*
X1448025Y43792D01*
X1448800Y42541D01*
X1449730Y41708D01*
X1450815Y41500D01*
X1451900Y41917D01*
X1452985Y43166D01*
G01X1462750Y41083D02*
X1462440Y41292D01*
Y41708D01*
X1462750Y41917D01*
X1463060Y41708D01*
Y41292D01*
X1462750Y41083D01*
G01Y46708D02*
X1462440Y46917D01*
Y47333D01*
X1462750Y47542D01*
X1463060Y47333D01*
Y46917D01*
X1462750Y46708D01*
G01X1472050Y41500D02*
Y54000D01*
X1475925D01*
X1477165Y53375D01*
X1477940Y52542D01*
X1478250Y50875D01*
X1477940Y49208D01*
X1477010Y48167D01*
X1475925Y47542D01*
X1472050D01*
G01X1475925D02*
X1478250Y41500D01*
G01X1485225Y47125D02*
X1490185D01*
X1489720Y48583D01*
X1488945Y49417D01*
X1487860Y49833D01*
X1486775Y49625D01*
X1485845Y49000D01*
X1485225Y47542D01*
X1484915Y46291D01*
Y45042D01*
X1485225Y43792D01*
X1486000Y42541D01*
X1486930Y41708D01*
X1488015Y41500D01*
X1489100Y41917D01*
X1490185Y43166D01*
G01X1499020Y41500D02*
Y52125D01*
X1499330Y53166D01*
X1499950Y53792D01*
X1500880Y54000D01*
X1501810Y53583D01*
X1502275Y52542D01*
G01X1500415Y49000D02*
X1497315D01*
G01X1510025Y47125D02*
X1514985D01*
X1514520Y48583D01*
X1513745Y49417D01*
X1512660Y49833D01*
X1511575Y49625D01*
X1510645Y49000D01*
X1510025Y47542D01*
X1509715Y46291D01*
Y45042D01*
X1510025Y43792D01*
X1510800Y42541D01*
X1511730Y41708D01*
X1512815Y41500D01*
X1513900Y41917D01*
X1514985Y43166D01*
G01X1522580Y41500D02*
Y49833D01*
G01Y48167D02*
X1523355Y49000D01*
X1524130Y49625D01*
X1525215Y49833D01*
X1525990Y49625D01*
X1526920Y49000D01*
G01X1549550Y54000D02*
Y41500D01*
G01X1547380Y49833D02*
X1551720D01*
G01X1561950Y41500D02*
X1561020Y41708D01*
X1560090Y42541D01*
X1559470Y44000D01*
X1559160Y45667D01*
X1559470Y47333D01*
X1560090Y48792D01*
X1561020Y49625D01*
X1561950Y49833D01*
X1562880Y49625D01*
X1563810Y48792D01*
X1564430Y47333D01*
X1564585Y45667D01*
X1564430Y44000D01*
X1563810Y42541D01*
X1562880Y41708D01*
X1561950Y41500D01*
G01X1583340D02*
Y54000D01*
X1586440D01*
X1587680Y53375D01*
X1588610Y52542D01*
X1589385Y51292D01*
X1590005Y49833D01*
X1590160Y47750D01*
X1590005Y45667D01*
X1589385Y44208D01*
X1588610Y42958D01*
X1587680Y42125D01*
X1586440Y41500D01*
X1583340D01*
G01X1596050D02*
Y54000D01*
X1599925D01*
X1601165Y53375D01*
X1601940Y52542D01*
X1602250Y50875D01*
X1601940Y49208D01*
X1601010Y48167D01*
X1599925Y47542D01*
X1596050D01*
G01X1599925D02*
X1602250Y41500D01*
G01X1609690Y54000D02*
X1613410D01*
G01X1611550D02*
Y41500D01*
G01X1609690D02*
X1613410D01*
G01X1620850Y54000D02*
Y41500D01*
X1627050D01*
G01X1633250Y54000D02*
Y41500D01*
X1639450D01*
G01X1661150D02*
Y54000D01*
G01X1676340Y41500D02*
Y49833D01*
G01Y48375D02*
X1675720Y49208D01*
X1674790Y49625D01*
X1673705Y49833D01*
X1672620Y49417D01*
X1671690Y48583D01*
X1671070Y47333D01*
X1670760Y45667D01*
X1671070Y44000D01*
X1671690Y42750D01*
X1672620Y41917D01*
X1673705Y41500D01*
X1674790Y41708D01*
X1675720Y42333D01*
X1676340Y43166D01*
G01X1682695Y37750D02*
X1683625Y37333D01*
X1684865Y37750D01*
X1685640Y38583D01*
X1686260Y39625D01*
X1687190Y42958D01*
X1689205Y49833D01*
G01X1684245D02*
X1687190Y42958D01*
G01X1696025Y47125D02*
X1700985D01*
X1700520Y48583D01*
X1699745Y49417D01*
X1698660Y49833D01*
X1697575Y49625D01*
X1696645Y49000D01*
X1696025Y47542D01*
X1695715Y46291D01*
Y45042D01*
X1696025Y43792D01*
X1696800Y42541D01*
X1697730Y41708D01*
X1698815Y41500D01*
X1699900Y41917D01*
X1700985Y43166D01*
G01X1708580Y41500D02*
Y49833D01*
G01Y48167D02*
X1709355Y49000D01*
X1710130Y49625D01*
X1711215Y49833D01*
X1711990Y49625D01*
X1712920Y49000D01*
G01X1734620Y41500D02*
Y52125D01*
X1734930Y53166D01*
X1735550Y53792D01*
X1736480Y54000D01*
X1737410Y53583D01*
X1737875Y52542D01*
G01X1736015Y49000D02*
X1732915D01*
G01X1747950Y41500D02*
X1747020Y41708D01*
X1746090Y42541D01*
X1745470Y44000D01*
X1745160Y45667D01*
X1745470Y47333D01*
X1746090Y48792D01*
X1747020Y49625D01*
X1747950Y49833D01*
X1748880Y49625D01*
X1749810Y48792D01*
X1750430Y47333D01*
X1750585Y45667D01*
X1750430Y44000D01*
X1749810Y42541D01*
X1748880Y41708D01*
X1747950Y41500D01*
G01X1758180D02*
Y49833D01*
G01Y48167D02*
X1758955Y49000D01*
X1759730Y49625D01*
X1760815Y49833D01*
X1761590Y49625D01*
X1762520Y49000D01*
G01X1788250Y41500D02*
X1782050D01*
Y54000D01*
X1788250D01*
G01X1785770Y47958D02*
X1782050D01*
G01X1794450Y54000D02*
Y41500D01*
X1800650D01*
G01X1806850Y54000D02*
Y41500D01*
X1813050D01*
G01X1820490Y54000D02*
X1824210D01*
G01X1822350D02*
Y41500D01*
G01X1820490D02*
X1824210D01*
G01X1831650D02*
Y54000D01*
X1835370D01*
X1836610Y53375D01*
X1837540Y51917D01*
X1837850Y50250D01*
X1837540Y48583D01*
X1836765Y47333D01*
X1835370Y46708D01*
X1831650D01*
G01X1843895Y43166D02*
X1845135Y42125D01*
X1846530Y41500D01*
X1847770D01*
X1849010Y42125D01*
X1849940Y43166D01*
X1850405Y44625D01*
X1850095Y46083D01*
X1849320Y47333D01*
X1847925Y48167D01*
X1846065Y48583D01*
X1844980Y49417D01*
X1844515Y50875D01*
X1844825Y52333D01*
X1845600Y53375D01*
X1846685Y54000D01*
X1847770D01*
X1848855Y53583D01*
X1849785Y52542D01*
G01X1862650Y41500D02*
X1856450D01*
Y54000D01*
X1862650D01*
G01X1860170Y47958D02*
X1856450D01*
G01X1887140Y54000D02*
Y41500D01*
G01Y43375D02*
X1886520Y42333D01*
X1885590Y41708D01*
X1884505Y41500D01*
X1883265Y41917D01*
X1882335Y42958D01*
X1881715Y44208D01*
X1881560Y45667D01*
X1881715Y47125D01*
X1882335Y48375D01*
X1883265Y49417D01*
X1884505Y49833D01*
X1885590Y49625D01*
X1886365Y49208D01*
X1887140Y48375D01*
G01X1894580Y41500D02*
Y49833D01*
G01Y48167D02*
X1895355Y49000D01*
X1896130Y49625D01*
X1897215Y49833D01*
X1897990Y49625D01*
X1898920Y49000D01*
G01X1909150Y49833D02*
Y41500D01*
G01Y53166D02*
X1908840Y53375D01*
Y53792D01*
X1909150Y54000D01*
X1909460Y53792D01*
Y53375D01*
X1909150Y53166D01*
G01X1921550Y41500D02*
Y54000D01*
G01X1933950Y41500D02*
Y54000D01*
G01X1961540D02*
Y41500D01*
G01Y43375D02*
X1960920Y42333D01*
X1959990Y41708D01*
X1958905Y41500D01*
X1957665Y41917D01*
X1956735Y42958D01*
X1956115Y44208D01*
X1955960Y45667D01*
X1956115Y47125D01*
X1956735Y48375D01*
X1957665Y49417D01*
X1958905Y49833D01*
X1959990Y49625D01*
X1960765Y49208D01*
X1961540Y48375D01*
G01X1971150Y49833D02*
Y41500D01*
G01Y53166D02*
X1970840Y53375D01*
Y53792D01*
X1971150Y54000D01*
X1971460Y53792D01*
Y53375D01*
X1971150Y53166D01*
G01X1981380Y41500D02*
Y49833D01*
G01Y48167D02*
X1982155Y49000D01*
X1982930Y49625D01*
X1984015Y49833D01*
X1984790Y49625D01*
X1985720Y49000D01*
G01X1993625Y47125D02*
X1998585D01*
X1998120Y48583D01*
X1997345Y49417D01*
X1996260Y49833D01*
X1995175Y49625D01*
X1994245Y49000D01*
X1993625Y47542D01*
X1993315Y46291D01*
Y45042D01*
X1993625Y43792D01*
X1994400Y42541D01*
X1995330Y41708D01*
X1996415Y41500D01*
X1997500Y41917D01*
X1998585Y43166D01*
G01X2010830Y48792D02*
X2009745Y49625D01*
X2008815Y49833D01*
X2007575Y49417D01*
X2006645Y48583D01*
X2006025Y47125D01*
X2005870Y45667D01*
X2006025Y44208D01*
X2006645Y42958D01*
X2007575Y41917D01*
X2008815Y41500D01*
X2009900Y41917D01*
X2010830Y42750D01*
G01X2020750Y54000D02*
Y41500D01*
G01X2018580Y49833D02*
X2022920D01*
G01X2033150D02*
Y41500D01*
G01Y53166D02*
X2032840Y53375D01*
Y53792D01*
X2033150Y54000D01*
X2033460Y53792D01*
Y53375D01*
X2033150Y53166D01*
G01X2045550Y41500D02*
X2044620Y41708D01*
X2043690Y42541D01*
X2043070Y44000D01*
X2042760Y45667D01*
X2043070Y47333D01*
X2043690Y48792D01*
X2044620Y49625D01*
X2045550Y49833D01*
X2046480Y49625D01*
X2047410Y48792D01*
X2048030Y47333D01*
X2048185Y45667D01*
X2048030Y44000D01*
X2047410Y42541D01*
X2046480Y41708D01*
X2045550Y41500D01*
G01X2055315D02*
Y49833D01*
G01Y47750D02*
X2055935Y48792D01*
X2056865Y49625D01*
X2058105Y49833D01*
X2059190Y49625D01*
X2060120Y48792D01*
X2060585Y47333D01*
Y41500D01*
G01X1408500Y99600D02*
X1892100D01*
G01X1408500Y71500D02*
Y377500D01*
X1892100D01*
Y71500D01*
X1408500D01*
G01Y127700D02*
X1892100D01*
G01X1408500Y155800D02*
X1892100D01*
G01X1408500Y183900D02*
X1892100D01*
G01X1408500Y212000D02*
X1892100D01*
G01X1408500Y240100D02*
X1892100D01*
G01X1408500Y268200D02*
X1892100D01*
G01X1408500Y296300D02*
X1892100D01*
G01X1419505Y305650D02*
Y318150D01*
X1425395D01*
G01X1423225Y312108D02*
X1419505D01*
G01X1432990Y318150D02*
X1436710D01*
G01X1434850D02*
Y305650D01*
G01X1432990D02*
X1436710D01*
G01X1448180Y311900D02*
X1451280D01*
Y308150D01*
X1450350Y306900D01*
X1449265Y306067D01*
X1447715Y305650D01*
X1446165Y306067D01*
X1445080Y306900D01*
X1444150Y308150D01*
X1443530Y309608D01*
X1443220Y311275D01*
Y312733D01*
X1443530Y313983D01*
X1444150Y315442D01*
X1445080Y316692D01*
X1446010Y317525D01*
X1447250Y318150D01*
X1448335D01*
X1449575Y317733D01*
X1450505Y316900D01*
G01X1456240Y318150D02*
Y309192D01*
X1456860Y307316D01*
X1458100Y306067D01*
X1459650Y305650D01*
X1461200Y306067D01*
X1462440Y307316D01*
X1463060Y309192D01*
Y318150D01*
G01X1468950Y305650D02*
Y318150D01*
X1472825D01*
X1474065Y317525D01*
X1474840Y316692D01*
X1475150Y315025D01*
X1474840Y313358D01*
X1473910Y312317D01*
X1472825Y311692D01*
X1468950D01*
G01X1472825D02*
X1475150Y305650D01*
G01X1487550D02*
X1481350D01*
Y318150D01*
X1487550D01*
G01X1485070Y312108D02*
X1481350D01*
G01X1408500Y324400D02*
X1892100D01*
G01X1408500Y352500D02*
X1892100D01*
G01X1491890Y358750D02*
Y371250D01*
X1494990D01*
X1496230Y370625D01*
X1497160Y369792D01*
X1497935Y368542D01*
X1498555Y367083D01*
X1498710Y365000D01*
X1498555Y362917D01*
X1497935Y361458D01*
X1497160Y360208D01*
X1496230Y359375D01*
X1494990Y358750D01*
X1491890D01*
G01X1504600D02*
Y371250D01*
X1508475D01*
X1509715Y370625D01*
X1510490Y369792D01*
X1510800Y368125D01*
X1510490Y366458D01*
X1509560Y365417D01*
X1508475Y364792D01*
X1504600D01*
G01X1508475D02*
X1510800Y358750D01*
G01X1518240Y371250D02*
X1521960D01*
G01X1520100D02*
Y358750D01*
G01X1518240D02*
X1521960D01*
G01X1529400Y371250D02*
Y358750D01*
X1535600D01*
G01X1541800Y371250D02*
Y358750D01*
X1548000D01*
G01X1573110Y370208D02*
X1572180Y370833D01*
X1571095Y371250D01*
X1569855D01*
X1568460Y370625D01*
X1567375Y369583D01*
X1566600Y368333D01*
X1565980Y366250D01*
X1565825Y364375D01*
X1566135Y362500D01*
X1566600Y361250D01*
X1567530Y360000D01*
X1568615Y359167D01*
X1569700Y358750D01*
X1570785D01*
X1571870Y359167D01*
X1572800Y359791D01*
X1573575Y360625D01*
G01X1578845Y358750D02*
Y371250D01*
G01X1585355D02*
Y358750D01*
G01Y365000D02*
X1578845D01*
G01X1590625Y358750D02*
X1594500Y371250D01*
X1598375Y358750D01*
G01X1596980Y363125D02*
X1592020D01*
G01X1603800Y358750D02*
Y371250D01*
X1607675D01*
X1608915Y370625D01*
X1609690Y369792D01*
X1610000Y368125D01*
X1609690Y366458D01*
X1608760Y365417D01*
X1607675Y364792D01*
X1603800D01*
G01X1607675D02*
X1610000Y358750D01*
G01X1619300Y371250D02*
Y358750D01*
G01X1615735Y371250D02*
X1622865D01*
G01X1631700Y358333D02*
X1631390Y358542D01*
Y358958D01*
X1631700Y359167D01*
X1632010Y358958D01*
Y358542D01*
X1631700Y358333D01*
G01Y363958D02*
X1631390Y364167D01*
Y364583D01*
X1631700Y364792D01*
X1632010Y364583D01*
Y364167D01*
X1631700Y363958D01*
G01X1656500Y371250D02*
Y358750D01*
G01X1652935Y371250D02*
X1660065D01*
G01X1668900Y358750D02*
X1667660Y358958D01*
X1666575Y359791D01*
X1665645Y361042D01*
X1665025Y362500D01*
X1664715Y364167D01*
Y365833D01*
X1665025Y367500D01*
X1665645Y368958D01*
X1666575Y370208D01*
X1667660Y371042D01*
X1668900Y371250D01*
X1670140Y371042D01*
X1671225Y370208D01*
X1672155Y368958D01*
X1672775Y367500D01*
X1673085Y365833D01*
Y364167D01*
X1672775Y362500D01*
X1672155Y361042D01*
X1671225Y359791D01*
X1670140Y358958D01*
X1668900Y358750D01*
G01X1678200D02*
Y371250D01*
X1681920D01*
X1683160Y370625D01*
X1684090Y369167D01*
X1684400Y367500D01*
X1684090Y365833D01*
X1683315Y364583D01*
X1681920Y363958D01*
X1678200D01*
G01X1706100Y371250D02*
Y358750D01*
G01X1703930Y367083D02*
X1708270D01*
G01X1718500Y358750D02*
X1717570Y358958D01*
X1716640Y359791D01*
X1716020Y361250D01*
X1715710Y362917D01*
X1716020Y364583D01*
X1716640Y366042D01*
X1717570Y366875D01*
X1718500Y367083D01*
X1719430Y366875D01*
X1720360Y366042D01*
X1720980Y364583D01*
X1721135Y362917D01*
X1720980Y361250D01*
X1720360Y359791D01*
X1719430Y358958D01*
X1718500Y358750D01*
G01X1744540Y365417D02*
X1745160Y366042D01*
X1745625Y367083D01*
X1745935Y368542D01*
X1745625Y369792D01*
X1745005Y370625D01*
X1743920Y371250D01*
X1739735D01*
Y358750D01*
X1744850D01*
X1745935Y359583D01*
X1746555Y360833D01*
X1746865Y362292D01*
X1746555Y363750D01*
X1745625Y365000D01*
X1744540Y365417D01*
X1739735D01*
G01X1755700Y358750D02*
X1754460Y358958D01*
X1753375Y359791D01*
X1752445Y361042D01*
X1751825Y362500D01*
X1751515Y364167D01*
Y365833D01*
X1751825Y367500D01*
X1752445Y368958D01*
X1753375Y370208D01*
X1754460Y371042D01*
X1755700Y371250D01*
X1756940Y371042D01*
X1758025Y370208D01*
X1758955Y368958D01*
X1759575Y367500D01*
X1759885Y365833D01*
Y364167D01*
X1759575Y362500D01*
X1758955Y361042D01*
X1758025Y359791D01*
X1756940Y358958D01*
X1755700Y358750D01*
G01X1768100Y371250D02*
Y358750D01*
G01X1764535Y371250D02*
X1771665D01*
G01X1780500D02*
Y358750D01*
G01X1776935Y371250D02*
X1784065D01*
G01X1792900Y358750D02*
X1791660Y358958D01*
X1790575Y359791D01*
X1789645Y361042D01*
X1789025Y362500D01*
X1788715Y364167D01*
Y365833D01*
X1789025Y367500D01*
X1789645Y368958D01*
X1790575Y370208D01*
X1791660Y371042D01*
X1792900Y371250D01*
X1794140Y371042D01*
X1795225Y370208D01*
X1796155Y368958D01*
X1796775Y367500D01*
X1797085Y365833D01*
Y364167D01*
X1796775Y362500D01*
X1796155Y361042D01*
X1795225Y359791D01*
X1794140Y358958D01*
X1792900Y358750D01*
G01X1801270D02*
Y371250D01*
X1805300Y360833D01*
X1809330Y371250D01*
Y358750D01*
G01X1498400Y324400D02*
Y71500D01*
G01X1522425Y333750D02*
X1526300Y346250D01*
X1530175Y333750D01*
G01X1528780Y338125D02*
X1523820D01*
G01X1535600Y346250D02*
Y333750D01*
X1541800D01*
G01X1548000Y346250D02*
Y333750D01*
X1554200D01*
G01X1572490Y346250D02*
Y337292D01*
X1573110Y335416D01*
X1574350Y334167D01*
X1575900Y333750D01*
X1577450Y334167D01*
X1578690Y335416D01*
X1579310Y337292D01*
Y346250D01*
G01X1584735Y333750D02*
Y346250D01*
X1591865Y333750D01*
Y346250D01*
G01X1598840D02*
X1602560D01*
G01X1600700D02*
Y333750D01*
G01X1598840D02*
X1602560D01*
G01X1613100Y346250D02*
Y333750D01*
G01X1609535Y346250D02*
X1616665D01*
G01X1622245Y335416D02*
X1623485Y334375D01*
X1624880Y333750D01*
X1626120D01*
X1627360Y334375D01*
X1628290Y335416D01*
X1628755Y336875D01*
X1628445Y338333D01*
X1627670Y339583D01*
X1626275Y340417D01*
X1624415Y340833D01*
X1623330Y341667D01*
X1622865Y343125D01*
X1623175Y344583D01*
X1623950Y345625D01*
X1625035Y346250D01*
X1626120D01*
X1627205Y345833D01*
X1628135Y344792D01*
G01X1646425Y333750D02*
X1650300Y346250D01*
X1654175Y333750D01*
G01X1652780Y338125D02*
X1647820D01*
G01X1659600Y333750D02*
Y346250D01*
X1663475D01*
X1664715Y345625D01*
X1665490Y344792D01*
X1665800Y343125D01*
X1665490Y341458D01*
X1664560Y340417D01*
X1663475Y339792D01*
X1659600D01*
G01X1663475D02*
X1665800Y333750D01*
G01X1678200D02*
X1672000D01*
Y346250D01*
X1678200D01*
G01X1675720Y340208D02*
X1672000D01*
G01X1698040Y346250D02*
X1701760D01*
G01X1699900D02*
Y333750D01*
G01X1698040D02*
X1701760D01*
G01X1708735D02*
Y346250D01*
X1715865Y333750D01*
Y346250D01*
G01X1733070Y333750D02*
Y346250D01*
X1737100Y335833D01*
X1741130Y346250D01*
Y333750D01*
G01X1747640Y346250D02*
X1751360D01*
G01X1749500D02*
Y333750D01*
G01X1747640D02*
X1751360D01*
G01X1758800Y346250D02*
Y333750D01*
X1765000D01*
G01X1771045Y335416D02*
X1772285Y334375D01*
X1773680Y333750D01*
X1774920D01*
X1776160Y334375D01*
X1777090Y335416D01*
X1777555Y336875D01*
X1777245Y338333D01*
X1776470Y339583D01*
X1775075Y340417D01*
X1773215Y340833D01*
X1772130Y341667D01*
X1771665Y343125D01*
X1771975Y344583D01*
X1772750Y345625D01*
X1773835Y346250D01*
X1774920D01*
X1776005Y345833D01*
X1776935Y344792D01*
G01X1568150Y79300D02*
Y91800D01*
X1566290Y89300D01*
G01Y79300D02*
X1570010D01*
G01X1577140Y81175D02*
X1578070Y80133D01*
X1579155Y79508D01*
X1580550Y79300D01*
X1581945Y79717D01*
X1583030Y80550D01*
X1583805Y82008D01*
X1583960Y83675D01*
X1583650Y85342D01*
X1582875Y86383D01*
X1581790Y87217D01*
X1580705Y87425D01*
X1579620Y87217D01*
X1578225Y86383D01*
X1578690Y91800D01*
X1582875D01*
G01X1592950Y79300D02*
X1594035Y79508D01*
X1595275Y80133D01*
X1596050Y81175D01*
X1596360Y82633D01*
X1596050Y84091D01*
X1595120Y85342D01*
X1593725Y85967D01*
X1592175D01*
X1591245Y86383D01*
X1590470Y87425D01*
X1590160Y88883D01*
X1590625Y90342D01*
X1591710Y91383D01*
X1592950Y91800D01*
X1594190Y91383D01*
X1595275Y90342D01*
X1595740Y88883D01*
X1595430Y87425D01*
X1594655Y86383D01*
X1593725Y85967D01*
X1592175D01*
X1590780Y85342D01*
X1589850Y84091D01*
X1589540Y82633D01*
X1589850Y81175D01*
X1590625Y80133D01*
X1591865Y79508D01*
X1592950Y79300D01*
G01X1605350Y78883D02*
X1605040Y79092D01*
Y79508D01*
X1605350Y79717D01*
X1605660Y79508D01*
Y79092D01*
X1605350Y78883D01*
G01X1617750Y91800D02*
X1616510Y91383D01*
X1615580Y90342D01*
X1614960Y89092D01*
X1614495Y87425D01*
X1614340Y85550D01*
X1614495Y83675D01*
X1614960Y82008D01*
X1615580Y80758D01*
X1616510Y79717D01*
X1617750Y79300D01*
X1618990Y79717D01*
X1619920Y80758D01*
X1620540Y82008D01*
X1621005Y83675D01*
X1621160Y85550D01*
X1621005Y87425D01*
X1620540Y89092D01*
X1619920Y90342D01*
X1618990Y91383D01*
X1617750Y91800D01*
G01X1574350Y107400D02*
X1575435Y107608D01*
X1576675Y108233D01*
X1577450Y109275D01*
X1577760Y110733D01*
X1577450Y112191D01*
X1576520Y113442D01*
X1575125Y114067D01*
X1573575D01*
X1572645Y114483D01*
X1571870Y115525D01*
X1571560Y116983D01*
X1572025Y118442D01*
X1573110Y119483D01*
X1574350Y119900D01*
X1575590Y119483D01*
X1576675Y118442D01*
X1577140Y116983D01*
X1576830Y115525D01*
X1576055Y114483D01*
X1575125Y114067D01*
X1573575D01*
X1572180Y113442D01*
X1571250Y112191D01*
X1570940Y110733D01*
X1571250Y109275D01*
X1572025Y108233D01*
X1573265Y107608D01*
X1574350Y107400D01*
G01X1583805Y112608D02*
X1584890Y114067D01*
X1585820Y114900D01*
X1587060Y115317D01*
X1588145Y114900D01*
X1588920Y114067D01*
X1589540Y112817D01*
X1589695Y111358D01*
X1589540Y110108D01*
X1588920Y108858D01*
X1587990Y107817D01*
X1586905Y107400D01*
X1585665Y107817D01*
X1584580Y109066D01*
X1583960Y110942D01*
X1583805Y113025D01*
X1584115Y115733D01*
X1584580Y117192D01*
X1585355Y118650D01*
X1586440Y119692D01*
X1587525Y119900D01*
X1588610Y119483D01*
X1589385Y118442D01*
G01X1599150Y106983D02*
X1598840Y107192D01*
Y107608D01*
X1599150Y107817D01*
X1599460Y107608D01*
Y107192D01*
X1599150Y106983D01*
G01X1611550Y119900D02*
X1610310Y119483D01*
X1609380Y118442D01*
X1608760Y117192D01*
X1608295Y115525D01*
X1608140Y113650D01*
X1608295Y111775D01*
X1608760Y110108D01*
X1609380Y108858D01*
X1610310Y107817D01*
X1611550Y107400D01*
X1612790Y107817D01*
X1613720Y108858D01*
X1614340Y110108D01*
X1614805Y111775D01*
X1614960Y113650D01*
X1614805Y115525D01*
X1614340Y117192D01*
X1613720Y118442D01*
X1612790Y119483D01*
X1611550Y119900D01*
G01X1568150Y135500D02*
Y148000D01*
X1566290Y145500D01*
G01Y135500D02*
X1570010D01*
G01X1577140Y137375D02*
X1578070Y136333D01*
X1579155Y135708D01*
X1580550Y135500D01*
X1581945Y135917D01*
X1583030Y136750D01*
X1583805Y138208D01*
X1583960Y139875D01*
X1583650Y141542D01*
X1582875Y142583D01*
X1581790Y143417D01*
X1580705Y143625D01*
X1579620Y143417D01*
X1578225Y142583D01*
X1578690Y148000D01*
X1582875D01*
G01X1592950Y135500D02*
X1594035Y135708D01*
X1595275Y136333D01*
X1596050Y137375D01*
X1596360Y138833D01*
X1596050Y140291D01*
X1595120Y141542D01*
X1593725Y142167D01*
X1592175D01*
X1591245Y142583D01*
X1590470Y143625D01*
X1590160Y145083D01*
X1590625Y146542D01*
X1591710Y147583D01*
X1592950Y148000D01*
X1594190Y147583D01*
X1595275Y146542D01*
X1595740Y145083D01*
X1595430Y143625D01*
X1594655Y142583D01*
X1593725Y142167D01*
X1592175D01*
X1590780Y141542D01*
X1589850Y140291D01*
X1589540Y138833D01*
X1589850Y137375D01*
X1590625Y136333D01*
X1591865Y135708D01*
X1592950Y135500D01*
G01X1605350Y135083D02*
X1605040Y135292D01*
Y135708D01*
X1605350Y135917D01*
X1605660Y135708D01*
Y135292D01*
X1605350Y135083D01*
G01X1617750Y148000D02*
X1616510Y147583D01*
X1615580Y146542D01*
X1614960Y145292D01*
X1614495Y143625D01*
X1614340Y141750D01*
X1614495Y139875D01*
X1614960Y138208D01*
X1615580Y136958D01*
X1616510Y135917D01*
X1617750Y135500D01*
X1618990Y135917D01*
X1619920Y136958D01*
X1620540Y138208D01*
X1621005Y139875D01*
X1621160Y141750D01*
X1621005Y143625D01*
X1620540Y145292D01*
X1619920Y146542D01*
X1618990Y147583D01*
X1617750Y148000D01*
G01X1568150Y163600D02*
Y176100D01*
X1566290Y173600D01*
G01Y163600D02*
X1570010D01*
G01X1582410D02*
Y176100D01*
X1576675Y167142D01*
X1584425D01*
G01X1592950Y176100D02*
X1591710Y175683D01*
X1590780Y174642D01*
X1590160Y173392D01*
X1589695Y171725D01*
X1589540Y169850D01*
X1589695Y167975D01*
X1590160Y166308D01*
X1590780Y165058D01*
X1591710Y164017D01*
X1592950Y163600D01*
X1594190Y164017D01*
X1595120Y165058D01*
X1595740Y166308D01*
X1596205Y167975D01*
X1596360Y169850D01*
X1596205Y171725D01*
X1595740Y173392D01*
X1595120Y174642D01*
X1594190Y175683D01*
X1592950Y176100D01*
G01X1605350Y163183D02*
X1605040Y163392D01*
Y163808D01*
X1605350Y164017D01*
X1605660Y163808D01*
Y163392D01*
X1605350Y163183D01*
G01X1617750Y176100D02*
X1616510Y175683D01*
X1615580Y174642D01*
X1614960Y173392D01*
X1614495Y171725D01*
X1614340Y169850D01*
X1614495Y167975D01*
X1614960Y166308D01*
X1615580Y165058D01*
X1616510Y164017D01*
X1617750Y163600D01*
X1618990Y164017D01*
X1619920Y165058D01*
X1620540Y166308D01*
X1621005Y167975D01*
X1621160Y169850D01*
X1621005Y171725D01*
X1620540Y173392D01*
X1619920Y174642D01*
X1618990Y175683D01*
X1617750Y176100D01*
G01X1576210Y191700D02*
Y204200D01*
X1570475Y195242D01*
X1578225D01*
G01X1586750Y191700D02*
X1587835Y191908D01*
X1589075Y192533D01*
X1589850Y193575D01*
X1590160Y195033D01*
X1589850Y196491D01*
X1588920Y197742D01*
X1587525Y198367D01*
X1585975D01*
X1585045Y198783D01*
X1584270Y199825D01*
X1583960Y201283D01*
X1584425Y202742D01*
X1585510Y203783D01*
X1586750Y204200D01*
X1587990Y203783D01*
X1589075Y202742D01*
X1589540Y201283D01*
X1589230Y199825D01*
X1588455Y198783D01*
X1587525Y198367D01*
X1585975D01*
X1584580Y197742D01*
X1583650Y196491D01*
X1583340Y195033D01*
X1583650Y193575D01*
X1584425Y192533D01*
X1585665Y191908D01*
X1586750Y191700D01*
G01X1599150Y191283D02*
X1598840Y191492D01*
Y191908D01*
X1599150Y192117D01*
X1599460Y191908D01*
Y191492D01*
X1599150Y191283D01*
G01X1611550Y204200D02*
X1610310Y203783D01*
X1609380Y202742D01*
X1608760Y201492D01*
X1608295Y199825D01*
X1608140Y197950D01*
X1608295Y196075D01*
X1608760Y194408D01*
X1609380Y193158D01*
X1610310Y192117D01*
X1611550Y191700D01*
X1612790Y192117D01*
X1613720Y193158D01*
X1614340Y194408D01*
X1614805Y196075D01*
X1614960Y197950D01*
X1614805Y199825D01*
X1614340Y201492D01*
X1613720Y202742D01*
X1612790Y203783D01*
X1611550Y204200D01*
G01X1576210Y219800D02*
Y232300D01*
X1570475Y223342D01*
X1578225D01*
G01X1586750Y219800D02*
Y232300D01*
X1584890Y229800D01*
G01Y219800D02*
X1588610D01*
G01X1599150Y219383D02*
X1598840Y219592D01*
Y220008D01*
X1599150Y220217D01*
X1599460Y220008D01*
Y219592D01*
X1599150Y219383D01*
G01X1611550Y232300D02*
X1610310Y231883D01*
X1609380Y230842D01*
X1608760Y229592D01*
X1608295Y227925D01*
X1608140Y226050D01*
X1608295Y224175D01*
X1608760Y222508D01*
X1609380Y221258D01*
X1610310Y220217D01*
X1611550Y219800D01*
X1612790Y220217D01*
X1613720Y221258D01*
X1614340Y222508D01*
X1614805Y224175D01*
X1614960Y226050D01*
X1614805Y227925D01*
X1614340Y229592D01*
X1613720Y230842D01*
X1612790Y231883D01*
X1611550Y232300D01*
G01X1570940Y250400D02*
X1571870Y248941D01*
X1573110Y248108D01*
X1574505Y247900D01*
X1575745Y248108D01*
X1576985Y249150D01*
X1577760Y250400D01*
X1577915Y251650D01*
X1577605Y253108D01*
X1576520Y254150D01*
X1575435Y254567D01*
X1574040D01*
G01X1575435D02*
X1576365Y255192D01*
X1577140Y256233D01*
X1577450Y257483D01*
X1577140Y258733D01*
X1576365Y259775D01*
X1574970Y260400D01*
X1573575Y260192D01*
X1572180Y259358D01*
G01X1583805Y253108D02*
X1584890Y254567D01*
X1585820Y255400D01*
X1587060Y255817D01*
X1588145Y255400D01*
X1588920Y254567D01*
X1589540Y253317D01*
X1589695Y251858D01*
X1589540Y250608D01*
X1588920Y249358D01*
X1587990Y248317D01*
X1586905Y247900D01*
X1585665Y248317D01*
X1584580Y249566D01*
X1583960Y251442D01*
X1583805Y253525D01*
X1584115Y256233D01*
X1584580Y257692D01*
X1585355Y259150D01*
X1586440Y260192D01*
X1587525Y260400D01*
X1588610Y259983D01*
X1589385Y258942D01*
G01X1599150Y247483D02*
X1598840Y247692D01*
Y248108D01*
X1599150Y248317D01*
X1599460Y248108D01*
Y247692D01*
X1599150Y247483D01*
G01X1611550Y260400D02*
X1610310Y259983D01*
X1609380Y258942D01*
X1608760Y257692D01*
X1608295Y256025D01*
X1608140Y254150D01*
X1608295Y252275D01*
X1608760Y250608D01*
X1609380Y249358D01*
X1610310Y248317D01*
X1611550Y247900D01*
X1612790Y248317D01*
X1613720Y249358D01*
X1614340Y250608D01*
X1614805Y252275D01*
X1614960Y254150D01*
X1614805Y256025D01*
X1614340Y257692D01*
X1613720Y258942D01*
X1612790Y259983D01*
X1611550Y260400D01*
G01X1574350Y276000D02*
Y288500D01*
X1572490Y286000D01*
G01Y276000D02*
X1576210D01*
G01X1583805Y281208D02*
X1584890Y282667D01*
X1585820Y283500D01*
X1587060Y283917D01*
X1588145Y283500D01*
X1588920Y282667D01*
X1589540Y281417D01*
X1589695Y279958D01*
X1589540Y278708D01*
X1588920Y277458D01*
X1587990Y276417D01*
X1586905Y276000D01*
X1585665Y276417D01*
X1584580Y277666D01*
X1583960Y279542D01*
X1583805Y281625D01*
X1584115Y284333D01*
X1584580Y285792D01*
X1585355Y287250D01*
X1586440Y288292D01*
X1587525Y288500D01*
X1588610Y288083D01*
X1589385Y287042D01*
G01X1599150Y275583D02*
X1598840Y275792D01*
Y276208D01*
X1599150Y276417D01*
X1599460Y276208D01*
Y275792D01*
X1599150Y275583D01*
G01X1611550Y288500D02*
X1610310Y288083D01*
X1609380Y287042D01*
X1608760Y285792D01*
X1608295Y284125D01*
X1608140Y282250D01*
X1608295Y280375D01*
X1608760Y278708D01*
X1609380Y277458D01*
X1610310Y276417D01*
X1611550Y276000D01*
X1612790Y276417D01*
X1613720Y277458D01*
X1614340Y278708D01*
X1614805Y280375D01*
X1614960Y282250D01*
X1614805Y284125D01*
X1614340Y285792D01*
X1613720Y287042D01*
X1612790Y288083D01*
X1611550Y288500D01*
G01X1571095Y307316D02*
X1572335Y306275D01*
X1573730Y305650D01*
X1574970D01*
X1576210Y306275D01*
X1577140Y307316D01*
X1577605Y308775D01*
X1577295Y310233D01*
X1576520Y311483D01*
X1575125Y312317D01*
X1573265Y312733D01*
X1572180Y313567D01*
X1571715Y315025D01*
X1572025Y316483D01*
X1572800Y317525D01*
X1573885Y318150D01*
X1574970D01*
X1576055Y317733D01*
X1576985Y316692D01*
G01X1584890Y318150D02*
X1588610D01*
G01X1586750D02*
Y305650D01*
G01X1584890D02*
X1588610D01*
G01X1596205Y318150D02*
X1602095D01*
X1596205Y305650D01*
X1602095D01*
G01X1614650D02*
X1608450D01*
Y318150D01*
X1614650D01*
G01X1612170Y312108D02*
X1608450D01*
G01X1691685Y79300D02*
Y91800D01*
X1698815Y79300D01*
Y91800D01*
G01X1707650Y79300D02*
X1706410Y79508D01*
X1705325Y80341D01*
X1704395Y81592D01*
X1703775Y83050D01*
X1703465Y84717D01*
Y86383D01*
X1703775Y88050D01*
X1704395Y89508D01*
X1705325Y90758D01*
X1706410Y91592D01*
X1707650Y91800D01*
X1708890Y91592D01*
X1709975Y90758D01*
X1710905Y89508D01*
X1711525Y88050D01*
X1711835Y86383D01*
Y84717D01*
X1711525Y83050D01*
X1710905Y81592D01*
X1709975Y80341D01*
X1708890Y79508D01*
X1707650Y79300D01*
G01X1716485D02*
Y91800D01*
X1723615Y79300D01*
Y91800D01*
G01X1730435Y83467D02*
X1734465D01*
G01X1741750Y79300D02*
Y91800D01*
X1745470D01*
X1746710Y91175D01*
X1747640Y89717D01*
X1747950Y88050D01*
X1747640Y86383D01*
X1746865Y85133D01*
X1745470Y84508D01*
X1741750D01*
G01X1754150Y91800D02*
Y79300D01*
X1760350D01*
G01X1765775D02*
X1769650Y91800D01*
X1773525Y79300D01*
G01X1772130Y83675D02*
X1767170D01*
G01X1782050Y91800D02*
Y79300D01*
G01X1778485Y91800D02*
X1785615D01*
G01X1797550Y79300D02*
X1791350D01*
Y91800D01*
X1797550D01*
G01X1795070Y85758D02*
X1791350D01*
G01X1803440Y79300D02*
Y91800D01*
X1806540D01*
X1807780Y91175D01*
X1808710Y90342D01*
X1809485Y89092D01*
X1810105Y87633D01*
X1810260Y85550D01*
X1810105Y83467D01*
X1809485Y82008D01*
X1808710Y80758D01*
X1807780Y79925D01*
X1806540Y79300D01*
X1803440D01*
G01X1687500Y324400D02*
Y71500D01*
G01X1691685Y107400D02*
Y119900D01*
X1698815Y107400D01*
Y119900D01*
G01X1707650Y107400D02*
X1706410Y107608D01*
X1705325Y108441D01*
X1704395Y109692D01*
X1703775Y111150D01*
X1703465Y112817D01*
Y114483D01*
X1703775Y116150D01*
X1704395Y117608D01*
X1705325Y118858D01*
X1706410Y119692D01*
X1707650Y119900D01*
X1708890Y119692D01*
X1709975Y118858D01*
X1710905Y117608D01*
X1711525Y116150D01*
X1711835Y114483D01*
Y112817D01*
X1711525Y111150D01*
X1710905Y109692D01*
X1709975Y108441D01*
X1708890Y107608D01*
X1707650Y107400D01*
G01X1716485D02*
Y119900D01*
X1723615Y107400D01*
Y119900D01*
G01X1730435Y111567D02*
X1734465D01*
G01X1741750Y107400D02*
Y119900D01*
X1745470D01*
X1746710Y119275D01*
X1747640Y117817D01*
X1747950Y116150D01*
X1747640Y114483D01*
X1746865Y113233D01*
X1745470Y112608D01*
X1741750D01*
G01X1754150Y119900D02*
Y107400D01*
X1760350D01*
G01X1765775D02*
X1769650Y119900D01*
X1773525Y107400D01*
G01X1772130Y111775D02*
X1767170D01*
G01X1782050Y119900D02*
Y107400D01*
G01X1778485Y119900D02*
X1785615D01*
G01X1797550Y107400D02*
X1791350D01*
Y119900D01*
X1797550D01*
G01X1795070Y113858D02*
X1791350D01*
G01X1803440Y107400D02*
Y119900D01*
X1806540D01*
X1807780Y119275D01*
X1808710Y118442D01*
X1809485Y117192D01*
X1810105Y115733D01*
X1810260Y113650D01*
X1810105Y111567D01*
X1809485Y110108D01*
X1808710Y108858D01*
X1807780Y108025D01*
X1806540Y107400D01*
X1803440D01*
G01X1716950Y135500D02*
Y148000D01*
X1720670D01*
X1721910Y147375D01*
X1722840Y145917D01*
X1723150Y144250D01*
X1722840Y142583D01*
X1722065Y141333D01*
X1720670Y140708D01*
X1716950D01*
G01X1729350Y148000D02*
Y135500D01*
X1735550D01*
G01X1740975D02*
X1744850Y148000D01*
X1748725Y135500D01*
G01X1747330Y139875D02*
X1742370D01*
G01X1757250Y148000D02*
Y135500D01*
G01X1753685Y148000D02*
X1760815D01*
G01X1772750Y135500D02*
X1766550D01*
Y148000D01*
X1772750D01*
G01X1770270Y141958D02*
X1766550D01*
G01X1778640Y135500D02*
Y148000D01*
X1781740D01*
X1782980Y147375D01*
X1783910Y146542D01*
X1784685Y145292D01*
X1785305Y143833D01*
X1785460Y141750D01*
X1785305Y139667D01*
X1784685Y138208D01*
X1783910Y136958D01*
X1782980Y136125D01*
X1781740Y135500D01*
X1778640D01*
G01X1716950Y163600D02*
Y176100D01*
X1720670D01*
X1721910Y175475D01*
X1722840Y174017D01*
X1723150Y172350D01*
X1722840Y170683D01*
X1722065Y169433D01*
X1720670Y168808D01*
X1716950D01*
G01X1729350Y176100D02*
Y163600D01*
X1735550D01*
G01X1740975D02*
X1744850Y176100D01*
X1748725Y163600D01*
G01X1747330Y167975D02*
X1742370D01*
G01X1757250Y176100D02*
Y163600D01*
G01X1753685Y176100D02*
X1760815D01*
G01X1772750Y163600D02*
X1766550D01*
Y176100D01*
X1772750D01*
G01X1770270Y170058D02*
X1766550D01*
G01X1778640Y163600D02*
Y176100D01*
X1781740D01*
X1782980Y175475D01*
X1783910Y174642D01*
X1784685Y173392D01*
X1785305Y171933D01*
X1785460Y169850D01*
X1785305Y167767D01*
X1784685Y166308D01*
X1783910Y165058D01*
X1782980Y164225D01*
X1781740Y163600D01*
X1778640D01*
G01X1716950Y191700D02*
Y204200D01*
X1720670D01*
X1721910Y203575D01*
X1722840Y202117D01*
X1723150Y200450D01*
X1722840Y198783D01*
X1722065Y197533D01*
X1720670Y196908D01*
X1716950D01*
G01X1729350Y204200D02*
Y191700D01*
X1735550D01*
G01X1740975D02*
X1744850Y204200D01*
X1748725Y191700D01*
G01X1747330Y196075D02*
X1742370D01*
G01X1757250Y204200D02*
Y191700D01*
G01X1753685Y204200D02*
X1760815D01*
G01X1772750Y191700D02*
X1766550D01*
Y204200D01*
X1772750D01*
G01X1770270Y198158D02*
X1766550D01*
G01X1778640Y191700D02*
Y204200D01*
X1781740D01*
X1782980Y203575D01*
X1783910Y202742D01*
X1784685Y201492D01*
X1785305Y200033D01*
X1785460Y197950D01*
X1785305Y195867D01*
X1784685Y194408D01*
X1783910Y193158D01*
X1782980Y192325D01*
X1781740Y191700D01*
X1778640D01*
G01X1716950Y219800D02*
Y232300D01*
X1720670D01*
X1721910Y231675D01*
X1722840Y230217D01*
X1723150Y228550D01*
X1722840Y226883D01*
X1722065Y225633D01*
X1720670Y225008D01*
X1716950D01*
G01X1729350Y232300D02*
Y219800D01*
X1735550D01*
G01X1740975D02*
X1744850Y232300D01*
X1748725Y219800D01*
G01X1747330Y224175D02*
X1742370D01*
G01X1757250Y232300D02*
Y219800D01*
G01X1753685Y232300D02*
X1760815D01*
G01X1772750Y219800D02*
X1766550D01*
Y232300D01*
X1772750D01*
G01X1770270Y226258D02*
X1766550D01*
G01X1778640Y219800D02*
Y232300D01*
X1781740D01*
X1782980Y231675D01*
X1783910Y230842D01*
X1784685Y229592D01*
X1785305Y228133D01*
X1785460Y226050D01*
X1785305Y223967D01*
X1784685Y222508D01*
X1783910Y221258D01*
X1782980Y220425D01*
X1781740Y219800D01*
X1778640D01*
G01X1716950Y247900D02*
Y260400D01*
X1720670D01*
X1721910Y259775D01*
X1722840Y258317D01*
X1723150Y256650D01*
X1722840Y254983D01*
X1722065Y253733D01*
X1720670Y253108D01*
X1716950D01*
G01X1729350Y260400D02*
Y247900D01*
X1735550D01*
G01X1740975D02*
X1744850Y260400D01*
X1748725Y247900D01*
G01X1747330Y252275D02*
X1742370D01*
G01X1757250Y260400D02*
Y247900D01*
G01X1753685Y260400D02*
X1760815D01*
G01X1772750Y247900D02*
X1766550D01*
Y260400D01*
X1772750D01*
G01X1770270Y254358D02*
X1766550D01*
G01X1778640Y247900D02*
Y260400D01*
X1781740D01*
X1782980Y259775D01*
X1783910Y258942D01*
X1784685Y257692D01*
X1785305Y256233D01*
X1785460Y254150D01*
X1785305Y252067D01*
X1784685Y250608D01*
X1783910Y249358D01*
X1782980Y248525D01*
X1781740Y247900D01*
X1778640D01*
G01X1716950Y276000D02*
Y288500D01*
X1720670D01*
X1721910Y287875D01*
X1722840Y286417D01*
X1723150Y284750D01*
X1722840Y283083D01*
X1722065Y281833D01*
X1720670Y281208D01*
X1716950D01*
G01X1729350Y288500D02*
Y276000D01*
X1735550D01*
G01X1740975D02*
X1744850Y288500D01*
X1748725Y276000D01*
G01X1747330Y280375D02*
X1742370D01*
G01X1757250Y288500D02*
Y276000D01*
G01X1753685Y288500D02*
X1760815D01*
G01X1772750Y276000D02*
X1766550D01*
Y288500D01*
X1772750D01*
G01X1770270Y282458D02*
X1766550D01*
G01X1778640Y276000D02*
Y288500D01*
X1781740D01*
X1782980Y287875D01*
X1783910Y287042D01*
X1784685Y285792D01*
X1785305Y284333D01*
X1785460Y282250D01*
X1785305Y280167D01*
X1784685Y278708D01*
X1783910Y277458D01*
X1782980Y276625D01*
X1781740Y276000D01*
X1778640D01*
G01X1716950Y305650D02*
Y318150D01*
X1720670D01*
X1721910Y317525D01*
X1722840Y316067D01*
X1723150Y314400D01*
X1722840Y312733D01*
X1722065Y311483D01*
X1720670Y310858D01*
X1716950D01*
G01X1729350Y318150D02*
Y305650D01*
X1735550D01*
G01X1740975D02*
X1744850Y318150D01*
X1748725Y305650D01*
G01X1747330Y310025D02*
X1742370D01*
G01X1757250Y318150D02*
Y305650D01*
G01X1753685Y318150D02*
X1760815D01*
G01X1772750Y305650D02*
X1766550D01*
Y318150D01*
X1772750D01*
G01X1770270Y312108D02*
X1766550D01*
G01X1778640Y305650D02*
Y318150D01*
X1781740D01*
X1782980Y317525D01*
X1783910Y316692D01*
X1784685Y315442D01*
X1785305Y313983D01*
X1785460Y311900D01*
X1785305Y309817D01*
X1784685Y308358D01*
X1783910Y307108D01*
X1782980Y306275D01*
X1781740Y305650D01*
X1778640D01*
G01X1814600Y324400D02*
Y71500D01*
G01X1850405Y89717D02*
X1851335Y90966D01*
X1852420Y91592D01*
X1853660Y91800D01*
X1855210Y91383D01*
X1856295Y90342D01*
X1856605Y89092D01*
X1856450Y87841D01*
X1855830Y86800D01*
X1852730Y84717D01*
X1851335Y83258D01*
X1850405Y81175D01*
X1850095Y79300D01*
X1856605D01*
G01X1855210Y107400D02*
Y119900D01*
X1849475Y110942D01*
X1857225D01*
G01X1850405Y145917D02*
X1851335Y147166D01*
X1852420Y147792D01*
X1853660Y148000D01*
X1855210Y147583D01*
X1856295Y146542D01*
X1856605Y145292D01*
X1856450Y144041D01*
X1855830Y143000D01*
X1852730Y140917D01*
X1851335Y139458D01*
X1850405Y137375D01*
X1850095Y135500D01*
X1856605D01*
G01X1850405Y174017D02*
X1851335Y175266D01*
X1852420Y175892D01*
X1853660Y176100D01*
X1855210Y175683D01*
X1856295Y174642D01*
X1856605Y173392D01*
X1856450Y172141D01*
X1855830Y171100D01*
X1852730Y169017D01*
X1851335Y167558D01*
X1850405Y165475D01*
X1850095Y163600D01*
X1856605D01*
G01X1850405Y202117D02*
X1851335Y203366D01*
X1852420Y203992D01*
X1853660Y204200D01*
X1855210Y203783D01*
X1856295Y202742D01*
X1856605Y201492D01*
X1856450Y200241D01*
X1855830Y199200D01*
X1852730Y197117D01*
X1851335Y195658D01*
X1850405Y193575D01*
X1850095Y191700D01*
X1856605D01*
G01X1843740Y221675D02*
X1844670Y220633D01*
X1845755Y220008D01*
X1847150Y219800D01*
X1848545Y220217D01*
X1849630Y221050D01*
X1850405Y222508D01*
X1850560Y224175D01*
X1850250Y225842D01*
X1849475Y226883D01*
X1848390Y227717D01*
X1847305Y227925D01*
X1846220Y227717D01*
X1844825Y226883D01*
X1845290Y232300D01*
X1849475D01*
G01X1856605Y230217D02*
X1857535Y231466D01*
X1858620Y232092D01*
X1859860Y232300D01*
X1861410Y231883D01*
X1862495Y230842D01*
X1862805Y229592D01*
X1862650Y228341D01*
X1862030Y227300D01*
X1858930Y225217D01*
X1857535Y223758D01*
X1856605Y221675D01*
X1856295Y219800D01*
X1862805D01*
G01X1849940Y250400D02*
X1850870Y248941D01*
X1852110Y248108D01*
X1853505Y247900D01*
X1854745Y248108D01*
X1855985Y249150D01*
X1856760Y250400D01*
X1856915Y251650D01*
X1856605Y253108D01*
X1855520Y254150D01*
X1854435Y254567D01*
X1853040D01*
G01X1854435D02*
X1855365Y255192D01*
X1856140Y256233D01*
X1856450Y257483D01*
X1856140Y258733D01*
X1855365Y259775D01*
X1853970Y260400D01*
X1852575Y260192D01*
X1851180Y259358D01*
G01X1840640Y276000D02*
X1840950Y278708D01*
X1841415Y281000D01*
X1842035Y283083D01*
X1842810Y285375D01*
X1844050Y288500D01*
X1837850D01*
G01X1850715Y277458D02*
X1851800Y276417D01*
X1853040Y276000D01*
X1854280Y276417D01*
X1855365Y277666D01*
X1856140Y279542D01*
X1856450Y281417D01*
Y283708D01*
X1856140Y285583D01*
X1855365Y287250D01*
X1854435Y288083D01*
X1853350Y288500D01*
X1852110Y288083D01*
X1851180Y287250D01*
X1850560Y286000D01*
X1850250Y284333D01*
X1850560Y282875D01*
X1851335Y281417D01*
X1852265Y280583D01*
X1853350Y280375D01*
X1854590Y280791D01*
X1855520Y281833D01*
X1856450Y283708D01*
G01X1865750Y276000D02*
Y288500D01*
X1863890Y286000D01*
G01Y276000D02*
X1867610D01*
G01X1840950Y305650D02*
X1839710Y305858D01*
X1838625Y306691D01*
X1837695Y307942D01*
X1837075Y309400D01*
X1836765Y311067D01*
Y312733D01*
X1837075Y314400D01*
X1837695Y315858D01*
X1838625Y317108D01*
X1839710Y317942D01*
X1840950Y318150D01*
X1842190Y317942D01*
X1843275Y317108D01*
X1844205Y315858D01*
X1844825Y314400D01*
X1845135Y312733D01*
Y311067D01*
X1844825Y309400D01*
X1844205Y307942D01*
X1843275Y306691D01*
X1842190Y305858D01*
X1840950Y305650D01*
G01X1842190Y308983D02*
X1844050Y305650D01*
G01X1853350Y318150D02*
Y305650D01*
G01X1849785Y318150D02*
X1856915D01*
G01X1865750Y305650D02*
Y311275D01*
X1862650Y318150D01*
G01X1868850D02*
X1865750Y311275D01*
G01X620709Y114409D02*
Y334409D01*
G01X633676Y217709D02*
X634009Y218242D01*
X634209Y218842D01*
Y219376D01*
X634009Y219909D01*
X633676Y220309D01*
X633209Y220509D01*
X632742Y220376D01*
X632342Y220042D01*
X632076Y219442D01*
X631942Y218642D01*
X631676Y218176D01*
X631209Y217976D01*
X630742Y218109D01*
X630409Y218442D01*
X630209Y218909D01*
Y219376D01*
X630342Y219842D01*
X630676Y220242D01*
G01X634209Y223709D02*
X630209D01*
G01X631542Y228309D02*
X634209D01*
G01X630476D02*
X630409Y228176D01*
X630276D01*
X630209Y228309D01*
X630276Y228442D01*
X630409D01*
X630476Y228309D01*
G01X630209Y232909D02*
X634209D01*
G01X631542Y231976D02*
Y233842D01*
G01X621209Y226509D02*
X625209Y222509D01*
Y230509D01*
X621209Y226509D01*
X631209D01*
M02*
